FILE_TYPE = MACRO_DRAWING;
SET COLOR_WIRE YELLOW;
SET COLOR_PROP ORANGE;
SET COLOR_DOT WHITE;
SET COLOR_ARC YELLOW;
SET COLOR_BODY GREEN;
SET COLOR_NOTE PURPLE;
SET PROP_DISPLAY VALUE;
SET PAGE_NUMBER P79;
FORCEADD OFFPAGE..2
R 2
(-7875 2750);
FORCEPROP 2 LAST $XR2 139 
J 0
(-8339 2750);
DISPLAY 0.638298 (-8339 2750);
PAINT MONO (-8339 2750);
FORCEPROP 2 LAST $XR1 133 
J 0
(-8219 2750);
DISPLAY 0.638298 (-8219 2750);
PAINT MONO (-8219 2750);
FORCEPROP 2 LAST $XR0 83 
J 0
(-8099 2750);
DISPLAY 0.638298 (-8099 2750);
PAINT MONO (-8099 2750);
FORCEPROP 2 LAST CDS_LIB standard
J 0
(-7875 2750);
DISPLAY INVISIBLE (-7875 2750);
FORCEPROP 1 LAST OFFPAGE TRUE
J 2
(-8200 2625);
DISPLAY 0.872340 (-8200 2625);
PAINT GREEN (-8200 2625);
DISPLAY INVISIBLE (-8200 2625);
FORCEPROP 1 LAST COMMENT_BODY TRUE
J 2
(-7830 2655);
DISPLAY 0.872340 (-7830 2655);
PAINT GREEN (-7830 2655);
DISPLAY INVISIBLE (-7830 2655);
FORCEPROP 2 LAST PATH I1
J 0
(-8125 2800);
DISPLAY 0.680851 (-8125 2800);
DISPLAY INVISIBLE (-8125 2800);
FORCEADD OFFPAGE..4
R 2
(-7875 3350);
FORCEPROP 2 LAST $XR0 136 
J 0
(-8127 3350);
DISPLAY 0.638298 (-8127 3350);
PAINT MONO (-8127 3350);
FORCEPROP 2 LAST CDS_LIB standard
J 0
(-7875 3350);
DISPLAY INVISIBLE (-7875 3350);
FORCEPROP 1 LAST OFFPAGE TRUE
J 2
(-8200 3225);
DISPLAY 0.872340 (-8200 3225);
PAINT GREEN (-8200 3225);
DISPLAY INVISIBLE (-8200 3225);
FORCEPROP 1 LAST COMMENT_BODY TRUE
J 2
(-7850 3250);
DISPLAY 0.872340 (-7850 3250);
PAINT GREEN (-7850 3250);
DISPLAY INVISIBLE (-7850 3250);
FORCEPROP 2 LAST PATH I10
J 0
(-8150 3400);
DISPLAY 0.680851 (-8150 3400);
DISPLAY INVISIBLE (-8150 3400);
FORCEADD OFFPAGE..2
R 2
(-7875 3750);
FORCEPROP 2 LAST $XR0 131 
J 0
(-8130 3750);
DISPLAY 0.638298 (-8130 3750);
PAINT MONO (-8130 3750);
FORCEPROP 2 LAST CDS_LIB standard
J 0
(-7875 3750);
DISPLAY INVISIBLE (-7875 3750);
FORCEPROP 1 LAST OFFPAGE TRUE
J 2
(-8200 3625);
DISPLAY 0.872340 (-8200 3625);
PAINT GREEN (-8200 3625);
DISPLAY INVISIBLE (-8200 3625);
FORCEPROP 1 LAST COMMENT_BODY TRUE
J 2
(-7830 3655);
DISPLAY 0.872340 (-7830 3655);
PAINT GREEN (-7830 3655);
DISPLAY INVISIBLE (-7830 3655);
FORCEPROP 2 LAST PATH I100
J 0
(-8125 3800);
DISPLAY 0.680851 (-8125 3800);
DISPLAY INVISIBLE (-8125 3800);
FORCEADD OFFPAGE..2
R 2
(-7875 3700);
FORCEPROP 2 LAST $XR0 131 
J 0
(-8130 3700);
DISPLAY 0.638298 (-8130 3700);
PAINT MONO (-8130 3700);
FORCEPROP 2 LAST CDS_LIB standard
J 0
(-7875 3700);
DISPLAY INVISIBLE (-7875 3700);
FORCEPROP 1 LAST OFFPAGE TRUE
J 2
(-8200 3575);
DISPLAY 0.872340 (-8200 3575);
PAINT GREEN (-8200 3575);
DISPLAY INVISIBLE (-8200 3575);
FORCEPROP 1 LAST COMMENT_BODY TRUE
J 2
(-7830 3605);
DISPLAY 0.872340 (-7830 3605);
PAINT GREEN (-7830 3605);
DISPLAY INVISIBLE (-7830 3605);
FORCEPROP 2 LAST PATH I101
J 0
(-7825 3775);
DISPLAY 0.680851 (-7825 3775);
DISPLAY INVISIBLE (-7825 3775);
FORCEADD OFFPAGE..2
R 2
(-7875 3650);
FORCEPROP 2 LAST $XR0 131 
J 0
(-8130 3650);
DISPLAY 0.638298 (-8130 3650);
PAINT MONO (-8130 3650);
FORCEPROP 2 LAST CDS_LIB standard
J 0
(-7875 3650);
DISPLAY INVISIBLE (-7875 3650);
FORCEPROP 1 LAST OFFPAGE TRUE
J 2
(-8200 3525);
DISPLAY 0.872340 (-8200 3525);
PAINT GREEN (-8200 3525);
DISPLAY INVISIBLE (-8200 3525);
FORCEPROP 1 LAST COMMENT_BODY TRUE
J 2
(-7830 3555);
DISPLAY 0.872340 (-7830 3555);
PAINT GREEN (-7830 3555);
DISPLAY INVISIBLE (-7830 3555);
FORCEPROP 2 LAST PATH I102
J 0
(-7825 3725);
DISPLAY 0.680851 (-7825 3725);
DISPLAY INVISIBLE (-7825 3725);
FORCEADD OFFPAGE..1
R 2
(-1775 4300);
FORCEPROP 2 LAST $XR0 137 
J 0
(-1589 4300);
DISPLAY 0.638298 (-1589 4300);
PAINT MONO (-1589 4300);
FORCEPROP 2 LAST CDS_LIB standard
J 2
(-1775 4300);
DISPLAY INVISIBLE (-1775 4300);
FORCEPROP 1 LAST OFFPAGE TRUE
J 2
(-2105 4170);
PAINT GREEN (-2105 4170);
DISPLAY INVISIBLE (-2105 4170);
FORCEPROP 1 LAST COMMENT_BODY TRUE
J 2
(-1905 4200);
DISPLAY 1.106383 (-1905 4200);
PAINT PEACH (-1905 4200);
DISPLAY INVISIBLE (-1905 4200);
FORCEPROP 2 LAST PATH I103
J 0
(-1450 4350);
DISPLAY 0.680851 (-1450 4350);
DISPLAY INVISIBLE (-1450 4350);
FORCEADD OFFPAGE..2
(-1775 4350);
FORCEPROP 2 LAST $XR0 137 
J 0
(-1586 4350);
DISPLAY 0.638298 (-1586 4350);
PAINT MONO (-1586 4350);
FORCEPROP 2 LAST CDS_LIB standard
J 0
(-1775 4350);
DISPLAY INVISIBLE (-1775 4350);
FORCEPROP 1 LAST OFFPAGE TRUE
J 0
(-1450 4225);
DISPLAY 0.872340 (-1450 4225);
PAINT GREEN (-1450 4225);
DISPLAY INVISIBLE (-1450 4225);
FORCEPROP 1 LAST COMMENT_BODY TRUE
J 0
(-1820 4255);
DISPLAY 0.872340 (-1820 4255);
PAINT GREEN (-1820 4255);
DISPLAY INVISIBLE (-1820 4255);
FORCEPROP 2 LAST PATH I104
J 0
(-1575 4400);
DISPLAY 0.680851 (-1575 4400);
DISPLAY INVISIBLE (-1575 4400);
FORCEADD OFFPAGE..2
(-1775 4400);
FORCEPROP 2 LAST $XR0 137 
J 0
(-1586 4400);
DISPLAY 0.638298 (-1586 4400);
PAINT MONO (-1586 4400);
FORCEPROP 2 LAST CDS_LIB standard
J 0
(-1775 4400);
DISPLAY INVISIBLE (-1775 4400);
FORCEPROP 1 LAST OFFPAGE TRUE
J 0
(-1450 4275);
DISPLAY 0.872340 (-1450 4275);
PAINT GREEN (-1450 4275);
DISPLAY INVISIBLE (-1450 4275);
FORCEPROP 1 LAST COMMENT_BODY TRUE
J 0
(-1820 4305);
DISPLAY 0.872340 (-1820 4305);
PAINT GREEN (-1820 4305);
DISPLAY INVISIBLE (-1820 4305);
FORCEPROP 2 LAST PATH I105
J 0
(-1575 4450);
DISPLAY 0.680851 (-1575 4450);
DISPLAY INVISIBLE (-1575 4450);
FORCEADD OFFPAGE..2
(-1775 4450);
FORCEPROP 2 LAST $XR0 137 
J 0
(-1586 4450);
DISPLAY 0.638298 (-1586 4450);
PAINT MONO (-1586 4450);
FORCEPROP 2 LAST CDS_LIB standard
J 0
(-1775 4450);
DISPLAY INVISIBLE (-1775 4450);
FORCEPROP 1 LAST OFFPAGE TRUE
J 0
(-1450 4325);
DISPLAY 0.872340 (-1450 4325);
PAINT GREEN (-1450 4325);
DISPLAY INVISIBLE (-1450 4325);
FORCEPROP 1 LAST COMMENT_BODY TRUE
J 0
(-1820 4355);
DISPLAY 0.872340 (-1820 4355);
PAINT GREEN (-1820 4355);
DISPLAY INVISIBLE (-1820 4355);
FORCEPROP 2 LAST PATH I106
J 0
(-1575 4500);
DISPLAY 0.680851 (-1575 4500);
DISPLAY INVISIBLE (-1575 4500);
FORCEADD OFFPAGE..2
R 2
(-7875 3550);
FORCEPROP 2 LAST $XR0 137 
J 0
(-8130 3550);
DISPLAY 0.638298 (-8130 3550);
PAINT MONO (-8130 3550);
FORCEPROP 2 LAST CDS_LIB standard
J 0
(-7875 3550);
DISPLAY INVISIBLE (-7875 3550);
FORCEPROP 1 LAST OFFPAGE TRUE
J 2
(-8200 3425);
DISPLAY 0.872340 (-8200 3425);
PAINT GREEN (-8200 3425);
DISPLAY INVISIBLE (-8200 3425);
FORCEPROP 1 LAST COMMENT_BODY TRUE
J 2
(-7830 3455);
DISPLAY 0.872340 (-7830 3455);
PAINT GREEN (-7830 3455);
DISPLAY INVISIBLE (-7830 3455);
FORCEPROP 2 LAST PATH I107
J 0
(-7825 3625);
DISPLAY 0.680851 (-7825 3625);
DISPLAY INVISIBLE (-7825 3625);
FORCEADD OFFPAGE..4
R 2
(-9075 4150);
FORCEPROP 2 LAST $XR2 82 
J 0
(-9296 4222);
DISPLAY 0.638298 (-9296 4222);
PAINT MONO (-9296 4222);
FORCEPROP 2 LAST $XR1 145 
J 0
(-9296 4186);
DISPLAY 0.638298 (-9296 4186);
PAINT MONO (-9296 4186);
FORCEPROP 2 LAST $XR0 83 
J 0
(-9296 4150);
DISPLAY 0.638298 (-9296 4150);
PAINT MONO (-9296 4150);
FORCEPROP 2 LAST CDS_LIB standard
J 0
(-9075 4150);
DISPLAY INVISIBLE (-9075 4150);
FORCEPROP 1 LAST OFFPAGE TRUE
J 2
(-9400 4025);
DISPLAY 0.872340 (-9400 4025);
PAINT GREEN (-9400 4025);
DISPLAY INVISIBLE (-9400 4025);
FORCEPROP 1 LAST COMMENT_BODY TRUE
J 2
(-9050 4050);
DISPLAY 0.872340 (-9050 4050);
PAINT GREEN (-9050 4050);
DISPLAY INVISIBLE (-9050 4050);
FORCEPROP 2 LAST PATH I108
J 0
(-9025 4225);
DISPLAY 0.680851 (-9025 4225);
DISPLAY INVISIBLE (-9025 4225);
FORCEADD OFFPAGE..4
R 2
(-7875 3800);
FORCEPROP 2 LAST $XR0 144 
J 0
(-8127 3800);
DISPLAY 0.638298 (-8127 3800);
PAINT MONO (-8127 3800);
FORCEPROP 2 LAST CDS_LIB standard
J 0
(-7875 3800);
DISPLAY INVISIBLE (-7875 3800);
FORCEPROP 1 LAST OFFPAGE TRUE
J 2
(-8200 3675);
DISPLAY 0.872340 (-8200 3675);
PAINT GREEN (-8200 3675);
DISPLAY INVISIBLE (-8200 3675);
FORCEPROP 1 LAST COMMENT_BODY TRUE
J 2
(-7850 3700);
DISPLAY 0.872340 (-7850 3700);
PAINT GREEN (-7850 3700);
DISPLAY INVISIBLE (-7850 3700);
FORCEPROP 2 LAST PATH I11
J 0
(-8125 3850);
DISPLAY 0.680851 (-8125 3850);
DISPLAY INVISIBLE (-8125 3850);
FORCEADD OFFPAGE..1
R 2
(-1775 4250);
FORCEPROP 2 LAST $XR0 151 
J 0
(-1589 4250);
DISPLAY 0.638298 (-1589 4250);
PAINT MONO (-1589 4250);
FORCEPROP 2 LAST CDS_LIB standard
J 2
(-1775 4250);
DISPLAY INVISIBLE (-1775 4250);
FORCEPROP 1 LAST OFFPAGE TRUE
J 2
(-2105 4120);
PAINT GREEN (-2105 4120);
DISPLAY INVISIBLE (-2105 4120);
FORCEPROP 1 LAST COMMENT_BODY TRUE
J 2
(-1905 4150);
DISPLAY 1.106383 (-1905 4150);
PAINT PEACH (-1905 4150);
DISPLAY INVISIBLE (-1905 4150);
FORCEPROP 2 LAST PATH I110
J 0
(-1600 4325);
DISPLAY 0.680851 (-1600 4325);
DISPLAY INVISIBLE (-1600 4325);
FORCEADD OFFPAGE..1
R 2
(-1775 4200);
FORCEPROP 2 LAST $XR0 151 
J 0
(-1589 4200);
DISPLAY 0.638298 (-1589 4200);
PAINT MONO (-1589 4200);
FORCEPROP 2 LAST CDS_LIB standard
J 2
(-1775 4200);
DISPLAY INVISIBLE (-1775 4200);
FORCEPROP 1 LAST OFFPAGE TRUE
J 2
(-2105 4070);
PAINT GREEN (-2105 4070);
DISPLAY INVISIBLE (-2105 4070);
FORCEPROP 1 LAST COMMENT_BODY TRUE
J 2
(-1905 4100);
DISPLAY 1.106383 (-1905 4100);
PAINT PEACH (-1905 4100);
DISPLAY INVISIBLE (-1905 4100);
FORCEPROP 2 LAST PATH I111
J 0
(-1600 4275);
DISPLAY 0.680851 (-1600 4275);
DISPLAY INVISIBLE (-1600 4275);
FORCEADD Q_RES..1
R 2
(-6825 4000);
FORCEPROP 1 LAST LOCATION R6095
J 0
(-7050 4000);
DISPLAY 0.489362 (-7050 4000);
PAINT SKYBLUE (-7050 4000);
FORCEPROP 0 LAST $SEC 1
J 0
(-6925 4050);
DISPLAY 0.680851 (-6925 4050);
PAINT MONO (-6925 4050);
DISPLAY INVISIBLE (-6925 4050);
FORCEPROP 0 LAST CDS_SEC 1
J 0
(-6925 4050);
DISPLAY 1.021277 (-6925 4050);
DISPLAY INVISIBLE (-6925 4050);
FORCEPROP 1 LASTPIN (-6725 4000) $PN 1
J 2
(-6737 4012);
DISPLAY 0.489362 (-6737 4012);
PAINT MONO (-6737 4012);
FORCEPROP 1 LASTPIN (-6925 4000) $PN 2
J 2
(-6887 4012);
DISPLAY 0.489362 (-6887 4012);
PAINT MONO (-6887 4012);
FORCEPROP 1 LAST VALUE 0
J 0
(-6700 4000);
DISPLAY 0.489362 (-6700 4000);
PAINT SKYBLUE (-6700 4000);
FORCEPROP 1 LAST MATERIAL CHIP
J 0
(-7000 3975);
DISPLAY 0.489362 (-7000 3975);
PAINT SKYBLUE (-7000 3975);
DISPLAY INVISIBLE (-7000 3975);
FORCEPROP 1 LAST PACK_TYPE 0402LF
J 0
(-7000 3925);
DISPLAY 0.489362 (-7000 3925);
PAINT SKYBLUE (-7000 3925);
DISPLAY INVISIBLE (-7000 3925);
FORCEPROP 1 LAST TOLERANCE 5%
J 2
(-6700 3975);
DISPLAY 0.489362 (-6700 3975);
PAINT SKYBLUE (-6700 3975);
DISPLAY INVISIBLE (-6700 3975);
FORCEPROP 1 LAST WATTAGE 1/16W
J 0
(-6750 3925);
DISPLAY 0.489362 (-6750 3925);
PAINT SKYBLUE (-6750 3925);
DISPLAY INVISIBLE (-6750 3925);
FORCEPROP 2 LAST CDS_LIB pure_quanta
J 0
(-6825 4000);
DISPLAY INVISIBLE (-6825 4000);
FORCEPROP 2 LAST BOM_COST MEM
J 0
(-6850 4150);
DISPLAY 0.744681 (-6850 4150);
PAINT WHITE (-6850 4150);
DISPLAY INVISIBLE (-6850 4150);
FORCEPROP 1 LAST PATH I112
J 2
(-6775 4150);
DISPLAY 0.978723 (-6775 4150);
PAINT WHITE (-6775 4150);
DISPLAY INVISIBLE (-6775 4150);
FORCEPROP 1 LAST PART_NUMBER CS00002JB13
J 0
(-6925 4050);
DISPLAY 0.489362 (-6925 4050);
PAINT SKYBLUE (-6925 4050);
DISPLAY INVISIBLE (-6925 4050);
FORCEADD OFFPAGE..4
R 2
(-7875 4000);
FORCEPROP 2 LAST $XR0 85 
J 0
(-8096 4000);
DISPLAY 0.638298 (-8096 4000);
PAINT MONO (-8096 4000);
FORCEPROP 2 LAST CDS_LIB standard
J 0
(-7875 4000);
DISPLAY INVISIBLE (-7875 4000);
FORCEPROP 1 LAST OFFPAGE TRUE
J 2
(-8200 3875);
DISPLAY 0.872340 (-8200 3875);
PAINT GREEN (-8200 3875);
DISPLAY INVISIBLE (-8200 3875);
FORCEPROP 1 LAST COMMENT_BODY TRUE
J 2
(-7850 3900);
DISPLAY 0.872340 (-7850 3900);
PAINT GREEN (-7850 3900);
DISPLAY INVISIBLE (-7850 3900);
FORCEPROP 2 LAST PATH I113
J 0
(-8125 4050);
DISPLAY 0.680851 (-8125 4050);
DISPLAY INVISIBLE (-8125 4050);
FORCEADD OFFPAGE..4
R 2
(-7875 3950);
FORCEPROP 2 LAST $XR0 269 
J 0
(-8127 3950);
DISPLAY 0.638298 (-8127 3950);
PAINT MONO (-8127 3950);
FORCEPROP 2 LAST CDS_LIB standard
J 0
(-7875 3950);
DISPLAY INVISIBLE (-7875 3950);
FORCEPROP 1 LAST OFFPAGE TRUE
J 2
(-8200 3825);
DISPLAY 0.872340 (-8200 3825);
PAINT GREEN (-8200 3825);
DISPLAY INVISIBLE (-8200 3825);
FORCEPROP 1 LAST COMMENT_BODY TRUE
J 2
(-7850 3850);
DISPLAY 0.872340 (-7850 3850);
PAINT GREEN (-7850 3850);
DISPLAY INVISIBLE (-7850 3850);
FORCEPROP 2 LAST PATH I114
J 0
(-8125 4000);
DISPLAY 0.680851 (-8125 4000);
DISPLAY INVISIBLE (-8125 4000);
FORCEADD Q_RES..1
R 2
(-6825 3950);
FORCEPROP 1 LAST LOCATION R6096
J 0
(-7050 3950);
DISPLAY 0.489362 (-7050 3950);
PAINT SKYBLUE (-7050 3950);
FORCEPROP 0 LAST $SEC 1
J 0
(-6925 4000);
DISPLAY 0.680851 (-6925 4000);
PAINT MONO (-6925 4000);
DISPLAY INVISIBLE (-6925 4000);
FORCEPROP 0 LAST CDS_SEC 1
J 0
(-6925 4000);
DISPLAY 1.021277 (-6925 4000);
DISPLAY INVISIBLE (-6925 4000);
FORCEPROP 1 LASTPIN (-6725 3950) $PN 1
J 2
(-6737 3962);
DISPLAY 0.489362 (-6737 3962);
PAINT MONO (-6737 3962);
FORCEPROP 1 LASTPIN (-6925 3950) $PN 2
J 2
(-6887 3962);
DISPLAY 0.489362 (-6887 3962);
PAINT MONO (-6887 3962);
FORCEPROP 1 LAST VALUE 0
J 0
(-6700 3950);
DISPLAY 0.489362 (-6700 3950);
PAINT SKYBLUE (-6700 3950);
FORCEPROP 1 LAST MATERIAL CHIP
J 0
(-7000 3925);
DISPLAY 0.489362 (-7000 3925);
PAINT SKYBLUE (-7000 3925);
DISPLAY INVISIBLE (-7000 3925);
FORCEPROP 2 LAST BOM_COST MEM
J 0
(-6850 4100);
DISPLAY 0.744681 (-6850 4100);
PAINT WHITE (-6850 4100);
DISPLAY INVISIBLE (-6850 4100);
FORCEPROP 2 LAST CDS_LIB pure_quanta
J 0
(-6825 3950);
DISPLAY INVISIBLE (-6825 3950);
FORCEPROP 1 LAST WATTAGE 1/16W
J 0
(-6750 3875);
DISPLAY 0.489362 (-6750 3875);
PAINT SKYBLUE (-6750 3875);
DISPLAY INVISIBLE (-6750 3875);
FORCEPROP 1 LAST TOLERANCE 5%
J 2
(-6700 3925);
DISPLAY 0.489362 (-6700 3925);
PAINT SKYBLUE (-6700 3925);
DISPLAY INVISIBLE (-6700 3925);
FORCEPROP 1 LAST PACK_TYPE 0402LF
J 0
(-7000 3875);
DISPLAY 0.489362 (-7000 3875);
PAINT SKYBLUE (-7000 3875);
DISPLAY INVISIBLE (-7000 3875);
FORCEPROP 1 LAST PATH I115
J 2
(-6775 4100);
DISPLAY 0.978723 (-6775 4100);
PAINT WHITE (-6775 4100);
DISPLAY INVISIBLE (-6775 4100);
FORCEPROP 1 LAST PART_NUMBER CS00002JB13
J 0
(-6925 4000);
DISPLAY 0.489362 (-6925 4000);
PAINT SKYBLUE (-6925 4000);
DISPLAY INVISIBLE (-6925 4000);
FORCEADD OFFPAGE..2
(-1775 3650);
FORCEPROP 2 LAST $XR0 257 
J 0
(-1586 3650);
DISPLAY 0.638298 (-1586 3650);
PAINT MONO (-1586 3650);
FORCEPROP 2 LAST CDS_LIB standard
J 0
(-1775 3650);
DISPLAY INVISIBLE (-1775 3650);
FORCEPROP 1 LAST OFFPAGE TRUE
J 0
(-1450 3525);
DISPLAY 0.872340 (-1450 3525);
PAINT GREEN (-1450 3525);
DISPLAY INVISIBLE (-1450 3525);
FORCEPROP 1 LAST COMMENT_BODY TRUE
J 0
(-1820 3555);
DISPLAY 0.872340 (-1820 3555);
PAINT GREEN (-1820 3555);
DISPLAY INVISIBLE (-1820 3555);
FORCEPROP 2 LAST PATH I116
J 0
(-975 3700);
DISPLAY 0.680851 (-975 3700);
DISPLAY INVISIBLE (-975 3700);
FORCEADD OFFPAGE..2
(-1775 3600);
FORCEPROP 2 LAST $XR0 257 
J 0
(-1586 3600);
DISPLAY 0.638298 (-1586 3600);
PAINT MONO (-1586 3600);
FORCEPROP 2 LAST CDS_LIB standard
J 0
(-1775 3600);
DISPLAY INVISIBLE (-1775 3600);
FORCEPROP 1 LAST OFFPAGE TRUE
J 0
(-1450 3475);
DISPLAY 0.872340 (-1450 3475);
PAINT GREEN (-1450 3475);
DISPLAY INVISIBLE (-1450 3475);
FORCEPROP 1 LAST COMMENT_BODY TRUE
J 0
(-1820 3505);
DISPLAY 0.872340 (-1820 3505);
PAINT GREEN (-1820 3505);
DISPLAY INVISIBLE (-1820 3505);
FORCEPROP 2 LAST PATH I117
J 0
(-1600 3675);
DISPLAY 0.680851 (-1600 3675);
DISPLAY INVISIBLE (-1600 3675);
FORCEADD OFFPAGE..2
(-1775 3500);
FORCEPROP 2 LAST $XR0 257 
J 0
(-1586 3500);
DISPLAY 0.638298 (-1586 3500);
PAINT MONO (-1586 3500);
FORCEPROP 2 LAST CDS_LIB standard
J 0
(-1775 3500);
DISPLAY INVISIBLE (-1775 3500);
FORCEPROP 1 LAST OFFPAGE TRUE
J 0
(-1450 3375);
DISPLAY 0.872340 (-1450 3375);
PAINT GREEN (-1450 3375);
DISPLAY INVISIBLE (-1450 3375);
FORCEPROP 1 LAST COMMENT_BODY TRUE
J 0
(-1820 3405);
DISPLAY 0.872340 (-1820 3405);
PAINT GREEN (-1820 3405);
DISPLAY INVISIBLE (-1820 3405);
FORCEPROP 2 LAST PATH I118
J 0
(-1600 3575);
DISPLAY 0.680851 (-1600 3575);
DISPLAY INVISIBLE (-1600 3575);
FORCEADD OFFPAGE..2
(-1775 3450);
FORCEPROP 2 LAST $XR0 257 
J 0
(-1586 3450);
DISPLAY 0.638298 (-1586 3450);
PAINT MONO (-1586 3450);
FORCEPROP 2 LAST CDS_LIB standard
J 0
(-1775 3450);
DISPLAY INVISIBLE (-1775 3450);
FORCEPROP 1 LAST OFFPAGE TRUE
J 0
(-1450 3325);
DISPLAY 0.872340 (-1450 3325);
PAINT GREEN (-1450 3325);
DISPLAY INVISIBLE (-1450 3325);
FORCEPROP 1 LAST COMMENT_BODY TRUE
J 0
(-1820 3355);
DISPLAY 0.872340 (-1820 3355);
PAINT GREEN (-1820 3355);
DISPLAY INVISIBLE (-1820 3355);
FORCEPROP 2 LAST PATH I119
J 0
(-1600 3525);
DISPLAY 0.680851 (-1600 3525);
DISPLAY INVISIBLE (-1600 3525);
FORCEADD OFFPAGE..4
R 2
(-7875 3850);
FORCEPROP 2 LAST $XR1 151 
J 0
(-8247 3850);
DISPLAY 0.638298 (-8247 3850);
PAINT MONO (-8247 3850);
FORCEPROP 2 LAST $XR0 150 
J 0
(-8127 3850);
DISPLAY 0.638298 (-8127 3850);
PAINT MONO (-8127 3850);
FORCEPROP 2 LAST CDS_LIB standard
J 0
(-7875 3850);
DISPLAY INVISIBLE (-7875 3850);
FORCEPROP 1 LAST OFFPAGE TRUE
J 2
(-8200 3725);
DISPLAY 0.872340 (-8200 3725);
PAINT GREEN (-8200 3725);
DISPLAY INVISIBLE (-8200 3725);
FORCEPROP 1 LAST COMMENT_BODY TRUE
J 2
(-7850 3750);
DISPLAY 0.872340 (-7850 3750);
PAINT GREEN (-7850 3750);
DISPLAY INVISIBLE (-7850 3750);
FORCEPROP 2 LAST PATH I12
J 0
(-8150 3900);
DISPLAY 0.680851 (-8150 3900);
DISPLAY INVISIBLE (-8150 3900);
FORCEADD OFFPAGE..2
(-1775 3250);
FORCEPROP 2 LAST $XR0 257 
J 0
(-1586 3250);
DISPLAY 0.638298 (-1586 3250);
PAINT MONO (-1586 3250);
FORCEPROP 2 LAST CDS_LIB standard
J 0
(-1775 3250);
DISPLAY INVISIBLE (-1775 3250);
FORCEPROP 1 LAST OFFPAGE TRUE
J 0
(-1450 3125);
DISPLAY 0.872340 (-1450 3125);
PAINT GREEN (-1450 3125);
DISPLAY INVISIBLE (-1450 3125);
FORCEPROP 1 LAST COMMENT_BODY TRUE
J 0
(-1820 3155);
DISPLAY 0.872340 (-1820 3155);
PAINT GREEN (-1820 3155);
DISPLAY INVISIBLE (-1820 3155);
FORCEPROP 2 LAST PATH I120
J 0
(-1600 3325);
DISPLAY 0.680851 (-1600 3325);
DISPLAY INVISIBLE (-1600 3325);
FORCEADD Q_RES..1
(-2775 4850);
FORCEPROP 1 LAST LOCATION R4145
J 0
(-2975 4850);
DISPLAY 0.510638 (-2975 4850);
FORCEPROP 2 LAST $SEC 1
J 0
(-2825 5050);
DISPLAY 0.680851 (-2825 5050);
PAINT MONO (-2825 5050);
DISPLAY INVISIBLE (-2825 5050);
FORCEPROP 2 LAST CDS_SEC 1
J 0
(-2825 5050);
DISPLAY 1.021277 (-2825 5050);
DISPLAY INVISIBLE (-2825 5050);
FORCEPROP 1 LASTPIN (-2875 4850) $PN 1
J 0
(-2863 4862);
DISPLAY 0.510638 (-2863 4862);
FORCEPROP 1 LASTPIN (-2675 4850) $PN 2
J 0
(-2713 4862);
DISPLAY 0.510638 (-2713 4862);
FORCEPROP 1 LAST VALUE 33.2
J 2
(-2575 4850);
DISPLAY 0.404255 (-2575 4850);
FORCEPROP 1 LAST MATERIAL CHIP
J 0
(-2475 4850);
DISPLAY 0.404255 (-2475 4850);
DISPLAY INVISIBLE (-2475 4850);
FORCEPROP 1 LAST TOLERANCE 1%
J 0
(-2550 4850);
DISPLAY 0.404255 (-2550 4850);
DISPLAY INVISIBLE (-2550 4850);
FORCEPROP 1 LAST WATTAGE 1/16W
J 2
(-2575 4975);
DISPLAY 0.638298 (-2575 4975);
DISPLAY INVISIBLE (-2575 4975);
FORCEPROP 1 LAST PACK_TYPE 0402LF
J 0
(-2925 4975);
DISPLAY 0.638298 (-2925 4975);
DISPLAY INVISIBLE (-2925 4975);
FORCEPROP 2 LAST CDS_LIB pure_quanta
J 0
(-2775 4850);
PAINT MONO (-2775 4850);
DISPLAY INVISIBLE (-2775 4850);
FORCEPROP 1 LAST PATH I121
J 0
(-2825 5000);
DISPLAY 0.978723 (-2825 5000);
PAINT WHITE (-2825 5000);
DISPLAY INVISIBLE (-2825 5000);
FORCEPROP 1 LAST PART_NUMBER CS03322FB03
J 0
(-2925 4925);
DISPLAY 0.638298 (-2925 4925);
DISPLAY INVISIBLE (-2925 4925);
FORCEADD Q_RES..1
(-2775 4800);
FORCEPROP 1 LAST LOCATION R4146
J 0
(-2975 4800);
DISPLAY 0.510638 (-2975 4800);
FORCEPROP 2 LAST $SEC 1
J 0
(-2825 5000);
DISPLAY 0.680851 (-2825 5000);
PAINT MONO (-2825 5000);
DISPLAY INVISIBLE (-2825 5000);
FORCEPROP 2 LAST CDS_SEC 1
J 0
(-2825 5000);
DISPLAY 1.021277 (-2825 5000);
DISPLAY INVISIBLE (-2825 5000);
FORCEPROP 1 LASTPIN (-2875 4800) $PN 1
J 0
(-2863 4812);
DISPLAY 0.510638 (-2863 4812);
FORCEPROP 1 LASTPIN (-2675 4800) $PN 2
J 0
(-2713 4812);
DISPLAY 0.510638 (-2713 4812);
FORCEPROP 1 LAST VALUE 33.2
J 2
(-2575 4800);
DISPLAY 0.404255 (-2575 4800);
FORCEPROP 1 LAST TOLERANCE 1%
J 0
(-2550 4800);
DISPLAY 0.404255 (-2550 4800);
DISPLAY INVISIBLE (-2550 4800);
FORCEPROP 1 LAST MATERIAL CHIP
J 0
(-2475 4800);
DISPLAY 0.404255 (-2475 4800);
DISPLAY INVISIBLE (-2475 4800);
FORCEPROP 1 LAST WATTAGE 1/16W
J 2
(-2575 4925);
DISPLAY 0.638298 (-2575 4925);
DISPLAY INVISIBLE (-2575 4925);
FORCEPROP 1 LAST PACK_TYPE 0402LF
J 0
(-2925 4925);
DISPLAY 0.638298 (-2925 4925);
DISPLAY INVISIBLE (-2925 4925);
FORCEPROP 2 LAST CDS_LIB pure_quanta
J 0
(-2775 4800);
PAINT MONO (-2775 4800);
DISPLAY INVISIBLE (-2775 4800);
FORCEPROP 1 LAST PATH I122
J 0
(-2825 4950);
DISPLAY 0.978723 (-2825 4950);
PAINT WHITE (-2825 4950);
DISPLAY INVISIBLE (-2825 4950);
FORCEPROP 1 LAST PART_NUMBER CS03322FB03
J 0
(-2925 4875);
DISPLAY 0.638298 (-2925 4875);
DISPLAY INVISIBLE (-2925 4875);
FORCEADD OFFPAGE..1
R 2
(-1775 4800);
FORCEPROP 2 LAST $XR0 125 
J 0
(-1589 4800);
DISPLAY 0.638298 (-1589 4800);
PAINT MONO (-1589 4800);
FORCEPROP 2 LAST CDS_LIB standard
J 0
(-1775 4800);
DISPLAY INVISIBLE (-1775 4800);
FORCEPROP 1 LAST OFFPAGE TRUE
J 2
(-2100 4675);
DISPLAY 0.872340 (-2100 4675);
PAINT GREEN (-2100 4675);
DISPLAY INVISIBLE (-2100 4675);
FORCEPROP 1 LAST COMMENT_BODY TRUE
J 2
(-1900 4700);
DISPLAY 0.872340 (-1900 4700);
PAINT GREEN (-1900 4700);
DISPLAY INVISIBLE (-1900 4700);
FORCEPROP 2 LAST PATH I123
J 0
(-1575 4850);
DISPLAY 0.680851 (-1575 4850);
DISPLAY INVISIBLE (-1575 4850);
FORCEADD OFFPAGE..1
R 2
(-1775 4850);
FORCEPROP 2 LAST $XR1 246 
J 0
(-1469 4850);
DISPLAY 0.638298 (-1469 4850);
PAINT MONO (-1469 4850);
FORCEPROP 2 LAST $XR0 125 
J 0
(-1589 4850);
DISPLAY 0.638298 (-1589 4850);
PAINT MONO (-1589 4850);
FORCEPROP 2 LAST CDS_LIB standard
J 0
(-1775 4850);
DISPLAY INVISIBLE (-1775 4850);
FORCEPROP 1 LAST OFFPAGE TRUE
J 2
(-2100 4725);
DISPLAY 0.872340 (-2100 4725);
PAINT GREEN (-2100 4725);
DISPLAY INVISIBLE (-2100 4725);
FORCEPROP 1 LAST COMMENT_BODY TRUE
J 2
(-1900 4750);
DISPLAY 0.872340 (-1900 4750);
PAINT GREEN (-1900 4750);
DISPLAY INVISIBLE (-1900 4750);
FORCEPROP 2 LAST PATH I124
J 0
(-1575 4900);
DISPLAY 0.680851 (-1575 4900);
DISPLAY INVISIBLE (-1575 4900);
FORCEADD OFFPAGE..4
R 2
(-9075 4300);
FORCEPROP 2 LAST $XR0 145 
J 0
(-9327 4300);
DISPLAY 0.638298 (-9327 4300);
PAINT MONO (-9327 4300);
FORCEPROP 2 LAST CDS_LIB standard
J 0
(-9075 4300);
DISPLAY INVISIBLE (-9075 4300);
FORCEPROP 1 LAST OFFPAGE TRUE
J 2
(-9400 4175);
DISPLAY 0.872340 (-9400 4175);
PAINT GREEN (-9400 4175);
DISPLAY INVISIBLE (-9400 4175);
FORCEPROP 1 LAST COMMENT_BODY TRUE
J 2
(-9050 4200);
DISPLAY 0.872340 (-9050 4200);
PAINT GREEN (-9050 4200);
DISPLAY INVISIBLE (-9050 4200);
FORCEPROP 2 LAST PATH I127
J 0
(-9325 4350);
DISPLAY 0.680851 (-9325 4350);
DISPLAY INVISIBLE (-9325 4350);
FORCEADD Q_RES..1
R 2
(-8450 4300);
FORCEPROP 1 LAST LOCATION R6094
J 0
(-8600 4275);
DISPLAY 0.489362 (-8600 4275);
PAINT SKYBLUE (-8600 4275);
FORCEPROP 0 LAST $SEC 1
J 0
(-8550 4350);
DISPLAY 0.680851 (-8550 4350);
PAINT MONO (-8550 4350);
DISPLAY INVISIBLE (-8550 4350);
FORCEPROP 0 LAST CDS_SEC 1
J 0
(-8550 4350);
DISPLAY 1.021277 (-8550 4350);
DISPLAY INVISIBLE (-8550 4350);
FORCEPROP 1 LASTPIN (-8350 4300) $PN 1
J 2
(-8362 4312);
DISPLAY 0.489362 (-8362 4312);
PAINT MONO (-8362 4312);
FORCEPROP 1 LASTPIN (-8550 4300) $PN 2
J 2
(-8512 4312);
DISPLAY 0.489362 (-8512 4312);
PAINT MONO (-8512 4312);
FORCEPROP 1 LAST VALUE 0
J 0
(-8325 4300);
DISPLAY 0.489362 (-8325 4300);
PAINT SKYBLUE (-8325 4300);
FORCEPROP 1 LAST MATERIAL EMPTY
J 0
(-8425 4275);
DISPLAY 0.489362 (-8425 4275);
PAINT SKYBLUE (-8425 4275);
FORCEPROP 1 LAST PACK_TYPE 0402LF
J 0
(-8625 4225);
DISPLAY 0.489362 (-8625 4225);
PAINT SKYBLUE (-8625 4225);
DISPLAY INVISIBLE (-8625 4225);
FORCEPROP 1 LAST TOLERANCE 5%
J 2
(-8325 4275);
DISPLAY 0.489362 (-8325 4275);
PAINT SKYBLUE (-8325 4275);
DISPLAY INVISIBLE (-8325 4275);
FORCEPROP 1 LAST WATTAGE 1/16W
J 0
(-8375 4225);
DISPLAY 0.489362 (-8375 4225);
PAINT SKYBLUE (-8375 4225);
DISPLAY INVISIBLE (-8375 4225);
FORCEPROP 2 LAST CDS_LIB pure_quanta
J 0
(-8450 4300);
DISPLAY INVISIBLE (-8450 4300);
FORCEPROP 2 LAST BOM_COST MEM
J 0
(-8475 4450);
DISPLAY 0.744681 (-8475 4450);
PAINT WHITE (-8475 4450);
DISPLAY INVISIBLE (-8475 4450);
FORCEPROP 1 LAST PATH I128
J 2
(-8400 4450);
DISPLAY 0.978723 (-8400 4450);
PAINT WHITE (-8400 4450);
DISPLAY INVISIBLE (-8400 4450);
FORCEPROP 1 LAST PART_NUMBER CS00002JB13
J 0
(-8550 4350);
DISPLAY 0.489362 (-8550 4350);
PAINT SKYBLUE (-8550 4350);
DISPLAY INVISIBLE (-8550 4350);
FORCEADD Q_RES..1
R 2
(-8450 4150);
FORCEPROP 1 LAST LOCATION R6116
J 0
(-8600 4125);
DISPLAY 0.489362 (-8600 4125);
PAINT SKYBLUE (-8600 4125);
FORCEPROP 0 LAST $SEC 1
J 0
(-8550 4200);
DISPLAY 0.680851 (-8550 4200);
PAINT MONO (-8550 4200);
DISPLAY INVISIBLE (-8550 4200);
FORCEPROP 0 LAST CDS_SEC 1
J 0
(-8550 4200);
DISPLAY 1.021277 (-8550 4200);
DISPLAY INVISIBLE (-8550 4200);
FORCEPROP 1 LASTPIN (-8350 4150) $PN 1
J 2
(-8362 4162);
DISPLAY 0.489362 (-8362 4162);
PAINT MONO (-8362 4162);
FORCEPROP 1 LASTPIN (-8550 4150) $PN 2
J 2
(-8512 4162);
DISPLAY 0.489362 (-8512 4162);
PAINT MONO (-8512 4162);
FORCEPROP 1 LAST MATERIAL CHIP
J 0
(-8425 4125);
DISPLAY 0.489362 (-8425 4125);
PAINT SKYBLUE (-8425 4125);
FORCEPROP 1 LAST VALUE 0
J 0
(-8325 4150);
DISPLAY 0.489362 (-8325 4150);
PAINT SKYBLUE (-8325 4150);
FORCEPROP 1 LAST PACK_TYPE 0402LF
J 0
(-8625 4075);
DISPLAY 0.489362 (-8625 4075);
PAINT SKYBLUE (-8625 4075);
DISPLAY INVISIBLE (-8625 4075);
FORCEPROP 1 LAST TOLERANCE 5%
J 2
(-8325 4125);
DISPLAY 0.489362 (-8325 4125);
PAINT SKYBLUE (-8325 4125);
DISPLAY INVISIBLE (-8325 4125);
FORCEPROP 1 LAST WATTAGE 1/16W
J 0
(-8375 4075);
DISPLAY 0.489362 (-8375 4075);
PAINT SKYBLUE (-8375 4075);
DISPLAY INVISIBLE (-8375 4075);
FORCEPROP 2 LAST CDS_LIB pure_quanta
J 0
(-8450 4150);
DISPLAY INVISIBLE (-8450 4150);
FORCEPROP 2 LAST BOM_COST MEM
J 0
(-8475 4300);
DISPLAY 0.744681 (-8475 4300);
PAINT WHITE (-8475 4300);
DISPLAY INVISIBLE (-8475 4300);
FORCEPROP 1 LAST PATH I129
J 2
(-8400 4300);
DISPLAY 0.978723 (-8400 4300);
PAINT WHITE (-8400 4300);
DISPLAY INVISIBLE (-8400 4300);
FORCEPROP 1 LAST PART_NUMBER CS00002JB13
J 0
(-8550 4200);
DISPLAY 0.489362 (-8550 4200);
PAINT SKYBLUE (-8550 4200);
DISPLAY INVISIBLE (-8550 4200);
FORCEADD OFFPAGE..2
R 2
(-7875 3900);
FORCEPROP 2 LAST $XR1 150 
J 0
(-8250 3900);
DISPLAY 0.638298 (-8250 3900);
PAINT MONO (-8250 3900);
FORCEPROP 2 LAST $XR0 151 
J 0
(-8130 3900);
DISPLAY 0.638298 (-8130 3900);
PAINT MONO (-8130 3900);
FORCEPROP 2 LAST CDS_LIB standard
J 0
(-7875 3900);
DISPLAY INVISIBLE (-7875 3900);
FORCEPROP 1 LAST OFFPAGE TRUE
J 2
(-8200 3775);
DISPLAY 0.872340 (-8200 3775);
PAINT GREEN (-8200 3775);
DISPLAY INVISIBLE (-8200 3775);
FORCEPROP 1 LAST COMMENT_BODY TRUE
J 2
(-7830 3805);
DISPLAY 0.872340 (-7830 3805);
PAINT GREEN (-7830 3805);
DISPLAY INVISIBLE (-7830 3805);
FORCEPROP 2 LAST PATH I13
J 0
(-8150 3950);
DISPLAY 0.680851 (-8150 3950);
DISPLAY INVISIBLE (-8150 3950);
FORCEADD OFFPAGE..3
(-1775 3750);
FORCEPROP 2 LAST $XR0 150 
J 0
(-1561 3750);
DISPLAY 0.638298 (-1561 3750);
PAINT MONO (-1561 3750);
FORCEPROP 2 LAST CDS_LIB standard
J 0
(-1775 3750);
DISPLAY INVISIBLE (-1775 3750);
FORCEPROP 1 LAST OFFPAGE TRUE
J 0
(-1450 3625);
DISPLAY 0.872340 (-1450 3625);
DISPLAY INVISIBLE (-1450 3625);
FORCEPROP 1 LAST COMMENT_BODY TRUE
J 0
(-1825 3650);
DISPLAY 0.872340 (-1825 3650);
PAINT GREEN (-1825 3650);
DISPLAY INVISIBLE (-1825 3650);
FORCEPROP 2 LAST PATH I130
J 0
(-1550 3800);
DISPLAY 0.680851 (-1550 3800);
DISPLAY INVISIBLE (-1550 3800);
FORCEADD Q_RES..1
R 2
(-2775 3950);
FORCEPROP 1 LAST LOCATION R6117
J 0
(-2975 3950);
DISPLAY 0.489362 (-2975 3950);
PAINT SKYBLUE (-2975 3950);
FORCEPROP 0 LAST $SEC 1
J 0
(-2825 4000);
DISPLAY 0.680851 (-2825 4000);
PAINT MONO (-2825 4000);
DISPLAY INVISIBLE (-2825 4000);
FORCEPROP 0 LAST CDS_SEC 1
J 0
(-2825 4000);
DISPLAY 1.021277 (-2825 4000);
DISPLAY INVISIBLE (-2825 4000);
FORCEPROP 1 LASTPIN (-2675 3950) $PN 1
J 2
(-2687 3962);
DISPLAY 0.489362 (-2687 3962);
PAINT MONO (-2687 3962);
FORCEPROP 1 LASTPIN (-2875 3950) $PN 2
J 2
(-2860 3960);
DISPLAY 0.489362 (-2860 3960);
PAINT MONO (-2860 3960);
FORCEPROP 1 LAST VALUE 100
J 0
(-2650 3950);
DISPLAY 0.489362 (-2650 3950);
PAINT SKYBLUE (-2650 3950);
FORCEPROP 1 LAST TOLERANCE 1%
J 2
(-2650 3925);
DISPLAY 0.489362 (-2650 3925);
PAINT SKYBLUE (-2650 3925);
DISPLAY INVISIBLE (-2650 3925);
FORCEPROP 1 LAST PACK_TYPE 0402LF
J 0
(-2950 3875);
DISPLAY 0.489362 (-2950 3875);
PAINT SKYBLUE (-2950 3875);
DISPLAY INVISIBLE (-2950 3875);
FORCEPROP 1 LAST MATERIAL CHIP
J 0
(-2950 3925);
DISPLAY 0.489362 (-2950 3925);
PAINT SKYBLUE (-2950 3925);
DISPLAY INVISIBLE (-2950 3925);
FORCEPROP 1 LAST WATTAGE 1/16W
J 0
(-2700 3875);
DISPLAY 0.489362 (-2700 3875);
PAINT SKYBLUE (-2700 3875);
DISPLAY INVISIBLE (-2700 3875);
FORCEPROP 2 LAST BOM_COST MEM
J 0
(-2800 4100);
DISPLAY 0.744681 (-2800 4100);
PAINT WHITE (-2800 4100);
DISPLAY INVISIBLE (-2800 4100);
FORCEPROP 2 LAST CDS_LIB pure_quanta
J 0
(-2775 3950);
DISPLAY INVISIBLE (-2775 3950);
FORCEPROP 1 LAST PATH I131
J 2
(-2725 4100);
DISPLAY 0.978723 (-2725 4100);
PAINT WHITE (-2725 4100);
DISPLAY INVISIBLE (-2725 4100);
FORCEPROP 1 LAST PART_NUMBER CS11002FB07
J 0
(-2875 4000);
DISPLAY 0.489362 (-2875 4000);
PAINT SKYBLUE (-2875 4000);
DISPLAY INVISIBLE (-2875 4000);
FORCEADD OFFPAGE..1
R 2
(-1775 3950);
FORCEPROP 2 LAST $XR0 140 
J 0
(-1589 3950);
DISPLAY 0.638298 (-1589 3950);
PAINT MONO (-1589 3950);
FORCEPROP 2 LAST CDS_LIB standard
J 2
(-1775 3950);
DISPLAY INVISIBLE (-1775 3950);
FORCEPROP 1 LAST OFFPAGE TRUE
J 2
(-2100 3825);
DISPLAY 0.872340 (-2100 3825);
DISPLAY INVISIBLE (-2100 3825);
FORCEPROP 1 LAST COMMENT_BODY TRUE
J 2
(-1900 3850);
DISPLAY 0.872340 (-1900 3850);
PAINT GREEN (-1900 3850);
DISPLAY INVISIBLE (-1900 3850);
FORCEPROP 2 LAST PATH I132
J 2
(-2000 4000);
DISPLAY 0.680851 (-2000 4000);
DISPLAY INVISIBLE (-2000 4000);
FORCEADD OFFPAGE..4
R 2
(-7875 2800);
FORCEPROP 2 LAST $XR0 84 
J 0
(-8096 2800);
DISPLAY 0.638298 (-8096 2800);
PAINT MONO (-8096 2800);
FORCEPROP 2 LAST CDS_LIB standard
J 0
(-7875 2800);
DISPLAY INVISIBLE (-7875 2800);
FORCEPROP 1 LAST OFFPAGE TRUE
J 2
(-8200 2675);
DISPLAY 0.872340 (-8200 2675);
PAINT GREEN (-8200 2675);
DISPLAY INVISIBLE (-8200 2675);
FORCEPROP 1 LAST COMMENT_BODY TRUE
J 2
(-7850 2700);
DISPLAY 0.872340 (-7850 2700);
PAINT GREEN (-7850 2700);
DISPLAY INVISIBLE (-7850 2700);
FORCEPROP 2 LAST PATH I133
J 0
(-8075 2850);
DISPLAY 0.680851 (-8075 2850);
DISPLAY INVISIBLE (-8075 2850);
FORCEADD OFFPAGE..4
R 2
(-7875 2850);
FORCEPROP 2 LAST $XR0 84 
J 0
(-8096 2850);
DISPLAY 0.638298 (-8096 2850);
PAINT MONO (-8096 2850);
FORCEPROP 2 LAST CDS_LIB standard
J 0
(-7875 2850);
DISPLAY INVISIBLE (-7875 2850);
FORCEPROP 1 LAST OFFPAGE TRUE
J 2
(-8200 2725);
DISPLAY 0.872340 (-8200 2725);
PAINT GREEN (-8200 2725);
DISPLAY INVISIBLE (-8200 2725);
FORCEPROP 1 LAST COMMENT_BODY TRUE
J 2
(-7850 2750);
DISPLAY 0.872340 (-7850 2750);
PAINT GREEN (-7850 2750);
DISPLAY INVISIBLE (-7850 2750);
FORCEPROP 2 LAST PATH I134
J 0
(-8075 2900);
DISPLAY 0.680851 (-8075 2900);
DISPLAY INVISIBLE (-8075 2900);
FORCEADD OFFPAGE..4
R 2
(-7875 3250);
FORCEPROP 2 LAST $XR0 84 
J 0
(-8096 3250);
DISPLAY 0.638298 (-8096 3250);
PAINT MONO (-8096 3250);
FORCEPROP 2 LAST CDS_LIB standard
J 0
(-7875 3250);
DISPLAY INVISIBLE (-7875 3250);
FORCEPROP 1 LAST OFFPAGE TRUE
J 2
(-8200 3125);
DISPLAY 0.872340 (-8200 3125);
PAINT GREEN (-8200 3125);
DISPLAY INVISIBLE (-8200 3125);
FORCEPROP 1 LAST COMMENT_BODY TRUE
J 2
(-7850 3150);
DISPLAY 0.872340 (-7850 3150);
PAINT GREEN (-7850 3150);
DISPLAY INVISIBLE (-7850 3150);
FORCEPROP 2 LAST PATH I135
J 0
(-8075 3300);
DISPLAY 0.680851 (-8075 3300);
DISPLAY INVISIBLE (-8075 3300);
FORCEADD OFFPAGE..4
R 2
(-7875 3200);
FORCEPROP 2 LAST $XR0 84 
J 0
(-8096 3200);
DISPLAY 0.638298 (-8096 3200);
PAINT MONO (-8096 3200);
FORCEPROP 2 LAST CDS_LIB standard
J 0
(-7875 3200);
DISPLAY INVISIBLE (-7875 3200);
FORCEPROP 1 LAST OFFPAGE TRUE
J 2
(-8200 3075);
DISPLAY 0.872340 (-8200 3075);
PAINT GREEN (-8200 3075);
DISPLAY INVISIBLE (-8200 3075);
FORCEPROP 1 LAST COMMENT_BODY TRUE
J 2
(-7850 3100);
DISPLAY 0.872340 (-7850 3100);
PAINT GREEN (-7850 3100);
DISPLAY INVISIBLE (-7850 3100);
FORCEPROP 2 LAST PATH I136
J 0
(-8075 3250);
DISPLAY 0.680851 (-8075 3250);
DISPLAY INVISIBLE (-8075 3250);
FORCEADD OFFPAGE..4
R 2
(-7875 4250);
FORCEPROP 2 LAST $XR0 84 
J 0
(-8096 4250);
DISPLAY 0.638298 (-8096 4250);
PAINT MONO (-8096 4250);
FORCEPROP 2 LAST CDS_LIB standard
J 0
(-7875 4250);
DISPLAY INVISIBLE (-7875 4250);
FORCEPROP 1 LAST OFFPAGE TRUE
J 2
(-8200 4125);
DISPLAY 0.872340 (-8200 4125);
PAINT GREEN (-8200 4125);
DISPLAY INVISIBLE (-8200 4125);
FORCEPROP 1 LAST COMMENT_BODY TRUE
J 2
(-7850 4150);
DISPLAY 0.872340 (-7850 4150);
PAINT GREEN (-7850 4150);
DISPLAY INVISIBLE (-7850 4150);
FORCEPROP 2 LAST PATH I137
J 0
(-8075 4300);
DISPLAY 0.680851 (-8075 4300);
DISPLAY INVISIBLE (-8075 4300);
FORCEADD Q_RES..1
R 2
(-2775 4750);
FORCEPROP 1 LAST LOCATION R407
J 0
(-2950 4750);
DISPLAY 0.489362 (-2950 4750);
PAINT SKYBLUE (-2950 4750);
FORCEPROP 0 LAST $SEC 1
J 0
(-2650 4775);
DISPLAY 0.680851 (-2650 4775);
PAINT MONO (-2650 4775);
DISPLAY INVISIBLE (-2650 4775);
FORCEPROP 0 LAST CDS_SEC 1
J 0
(-2650 4775);
DISPLAY 0.680851 (-2650 4775);
DISPLAY INVISIBLE (-2650 4775);
FORCEPROP 1 LASTPIN (-2675 4750) $PN 1
J 2
(-2687 4762);
DISPLAY 0.787234 (-2687 4762);
PAINT MONO (-2687 4762);
FORCEPROP 1 LASTPIN (-2875 4750) $PN 2
J 2
(-2837 4762);
DISPLAY 0.787234 (-2837 4762);
PAINT MONO (-2837 4762);
FORCEPROP 1 LAST VALUE 0
J 0
(-2650 4750);
DISPLAY 0.489362 (-2650 4750);
PAINT SKYBLUE (-2650 4750);
FORCEPROP 2 LAST BOM_COST MEM
J 0
(-2800 4900);
DISPLAY 0.744681 (-2800 4900);
PAINT WHITE (-2800 4900);
DISPLAY INVISIBLE (-2800 4900);
FORCEPROP 1 LAST WATTAGE 1/16W
J 0
(-2700 4675);
DISPLAY 0.489362 (-2700 4675);
PAINT SKYBLUE (-2700 4675);
DISPLAY INVISIBLE (-2700 4675);
FORCEPROP 1 LAST MATERIAL CHIP
J 0
(-2950 4725);
DISPLAY 0.489362 (-2950 4725);
PAINT SKYBLUE (-2950 4725);
DISPLAY INVISIBLE (-2950 4725);
FORCEPROP 1 LAST TOLERANCE 5%
J 2
(-2650 4725);
DISPLAY 0.489362 (-2650 4725);
PAINT SKYBLUE (-2650 4725);
DISPLAY INVISIBLE (-2650 4725);
FORCEPROP 1 LAST PACK_TYPE 0402LF
J 0
(-2950 4675);
DISPLAY 0.489362 (-2950 4675);
PAINT SKYBLUE (-2950 4675);
DISPLAY INVISIBLE (-2950 4675);
FORCEPROP 2 LAST CDS_LIB pure_quanta
J 0
(-2775 4750);
DISPLAY INVISIBLE (-2775 4750);
FORCEPROP 1 LAST PATH I139
J 2
(-2725 4900);
DISPLAY 0.978723 (-2725 4900);
PAINT WHITE (-2725 4900);
DISPLAY INVISIBLE (-2725 4900);
FORCEPROP 1 LAST PART_NUMBER CS00002JB13
J 0
(-2875 4800);
DISPLAY 0.489362 (-2875 4800);
PAINT SKYBLUE (-2875 4800);
DISPLAY INVISIBLE (-2875 4800);
FORCEADD OFFPAGE..1
R 2
(-1775 4750);
FORCEPROP 2 LAST $XR0 142 
J 0
(-1589 4750);
DISPLAY 0.638298 (-1589 4750);
PAINT MONO (-1589 4750);
FORCEPROP 2 LAST CDS_LIB standard
J 0
(-1775 4750);
DISPLAY INVISIBLE (-1775 4750);
FORCEPROP 1 LAST OFFPAGE TRUE
J 2
(-2100 4625);
DISPLAY 0.872340 (-2100 4625);
PAINT GREEN (-2100 4625);
DISPLAY INVISIBLE (-2100 4625);
FORCEPROP 1 LAST COMMENT_BODY TRUE
J 2
(-1900 4650);
DISPLAY 0.872340 (-1900 4650);
PAINT GREEN (-1900 4650);
DISPLAY INVISIBLE (-1900 4650);
FORCEPROP 2 LAST PATH I140
J 0
(-1600 4825);
DISPLAY 0.680851 (-1600 4825);
DISPLAY INVISIBLE (-1600 4825);
FORCEADD Q_RES..1
R 2
(-2775 3800);
FORCEPROP 1 LAST LOCATION R419
J 0
(-2975 3800);
DISPLAY 0.489362 (-2975 3800);
PAINT SKYBLUE (-2975 3800);
FORCEPROP 0 LAST $SEC 1
J 0
(-2650 3825);
DISPLAY 0.680851 (-2650 3825);
PAINT MONO (-2650 3825);
DISPLAY INVISIBLE (-2650 3825);
FORCEPROP 0 LAST CDS_SEC 1
J 0
(-2650 3825);
DISPLAY 0.680851 (-2650 3825);
DISPLAY INVISIBLE (-2650 3825);
FORCEPROP 1 LASTPIN (-2675 3800) $PN 1
J 2
(-2687 3812);
DISPLAY 0.787234 (-2687 3812);
PAINT MONO (-2687 3812);
FORCEPROP 1 LASTPIN (-2875 3800) $PN 2
J 2
(-2837 3812);
DISPLAY 0.787234 (-2837 3812);
PAINT MONO (-2837 3812);
FORCEPROP 1 LAST VALUE 0
J 0
(-2650 3800);
DISPLAY 0.489362 (-2650 3800);
PAINT SKYBLUE (-2650 3800);
FORCEPROP 1 LAST PACK_TYPE 0402LF
J 0
(-2950 3725);
DISPLAY 0.489362 (-2950 3725);
PAINT SKYBLUE (-2950 3725);
DISPLAY INVISIBLE (-2950 3725);
FORCEPROP 1 LAST TOLERANCE 5%
J 2
(-2650 3775);
DISPLAY 0.489362 (-2650 3775);
PAINT SKYBLUE (-2650 3775);
DISPLAY INVISIBLE (-2650 3775);
FORCEPROP 1 LAST MATERIAL CHIP
J 0
(-2950 3775);
DISPLAY 0.489362 (-2950 3775);
PAINT SKYBLUE (-2950 3775);
DISPLAY INVISIBLE (-2950 3775);
FORCEPROP 1 LAST WATTAGE 1/16W
J 0
(-2700 3725);
DISPLAY 0.489362 (-2700 3725);
PAINT SKYBLUE (-2700 3725);
DISPLAY INVISIBLE (-2700 3725);
FORCEPROP 2 LAST BOM_COST MEM
J 0
(-2800 3950);
DISPLAY 0.744681 (-2800 3950);
PAINT WHITE (-2800 3950);
DISPLAY INVISIBLE (-2800 3950);
FORCEPROP 2 LAST CDS_LIB pure_quanta
J 0
(-2775 3800);
DISPLAY INVISIBLE (-2775 3800);
FORCEPROP 1 LAST PATH I141
J 2
(-2725 3950);
DISPLAY 0.978723 (-2725 3950);
PAINT WHITE (-2725 3950);
DISPLAY INVISIBLE (-2725 3950);
FORCEPROP 1 LAST PART_NUMBER CS00002JB13
J 0
(-2875 3850);
DISPLAY 0.489362 (-2875 3850);
PAINT SKYBLUE (-2875 3850);
DISPLAY INVISIBLE (-2875 3850);
FORCEADD OFFPAGE..2
(-1775 3800);
FORCEPROP 2 LAST $XR0 150 
J 0
(-1586 3800);
DISPLAY 0.638298 (-1586 3800);
PAINT MONO (-1586 3800);
FORCEPROP 2 LAST CDS_LIB standard
J 0
(-1775 3800);
DISPLAY INVISIBLE (-1775 3800);
FORCEPROP 1 LAST OFFPAGE TRUE
J 0
(-1450 3675);
DISPLAY 0.872340 (-1450 3675);
PAINT GREEN (-1450 3675);
DISPLAY INVISIBLE (-1450 3675);
FORCEPROP 1 LAST COMMENT_BODY TRUE
J 0
(-1820 3705);
DISPLAY 0.872340 (-1820 3705);
PAINT GREEN (-1820 3705);
DISPLAY INVISIBLE (-1820 3705);
FORCEPROP 2 LAST PATH I142
J 0
(-1600 3875);
DISPLAY 0.680851 (-1600 3875);
DISPLAY INVISIBLE (-1600 3875);
FORCEADD OFFPAGE..1
R 2
(-1800 3150);
FORCEPROP 2 LAST $XR0 142 
J 0
(-1614 3150);
DISPLAY 0.638298 (-1614 3150);
PAINT MONO (-1614 3150);
FORCEPROP 2 LAST CDS_LIB standard
J 0
(-1800 3150);
DISPLAY INVISIBLE (-1800 3150);
FORCEPROP 1 LAST OFFPAGE TRUE
J 2
(-2125 3025);
DISPLAY 0.872340 (-2125 3025);
PAINT GREEN (-2125 3025);
DISPLAY INVISIBLE (-2125 3025);
FORCEPROP 1 LAST COMMENT_BODY TRUE
J 2
(-1925 3050);
DISPLAY 0.872340 (-1925 3050);
PAINT GREEN (-1925 3050);
DISPLAY INVISIBLE (-1925 3050);
FORCEPROP 2 LAST PATH I143
J 0
(-1625 3225);
DISPLAY 0.680851 (-1625 3225);
DISPLAY INVISIBLE (-1625 3225);
FORCEADD Q_RES..1
(-2775 3900);
FORCEPROP 1 LAST LOCATION R439
J 0
(-2950 3900);
DISPLAY 0.638298 (-2950 3900);
FORCEPROP 2 LAST SEC 1
J 0
(-2825 4100);
DISPLAY 0.680851 (-2825 4100);
PAINT MONO (-2825 4100);
DISPLAY INVISIBLE (-2825 4100);
FORCEPROP 1 LASTPIN (-2875 3900) $PN 1
J 0
(-2863 3912);
DISPLAY 0.638298 (-2863 3912);
PAINT MONO (-2863 3912);
FORCEPROP 1 LASTPIN (-2675 3900) $PN 2
J 0
(-2713 3912);
DISPLAY 0.638298 (-2713 3912);
PAINT MONO (-2713 3912);
FORCEPROP 1 LAST VALUE 0
J 2
(-2600 3900);
DISPLAY 0.638298 (-2600 3900);
FORCEPROP 1 LAST MATERIAL CHIP
J 0
(-2775 3750);
DISPLAY 0.638298 (-2775 3750);
DISPLAY INVISIBLE (-2775 3750);
FORCEPROP 1 LAST WATTAGE 1/16W
J 2
(-2800 3750);
DISPLAY 0.638298 (-2800 3750);
DISPLAY INVISIBLE (-2800 3750);
FORCEPROP 1 LAST TOLERANCE 5%
J 0
(-2775 3800);
DISPLAY 0.638298 (-2775 3800);
DISPLAY INVISIBLE (-2775 3800);
FORCEPROP 1 LAST PACK_TYPE 0402LF
J 0
(-2525 3750);
DISPLAY 0.638298 (-2525 3750);
DISPLAY INVISIBLE (-2525 3750);
FORCEPROP 2 LAST SEC_TYPE 0402LF
J 0
(-2825 4100);
DISPLAY 0.680851 (-2825 4100);
DISPLAY INVISIBLE (-2825 4100);
FORCEPROP 2 LAST CDS_LIB pure_quanta
J 0
(-2775 3900);
DISPLAY INVISIBLE (-2775 3900);
FORCEPROP 1 LAST PATH I144
J 0
(-2825 4050);
DISPLAY 0.978723 (-2825 4050);
PAINT WHITE (-2825 4050);
DISPLAY INVISIBLE (-2825 4050);
FORCEPROP 1 LAST PART_NUMBER CS00002JB13
J 0
(-2825 4000);
DISPLAY 0.638298 (-2825 4000);
DISPLAY INVISIBLE (-2825 4000);
FORCEADD OFFPAGE..1
R 2
(-1775 3900);
FORCEPROP 2 LAST $XR0 188 
J 0
(-1589 3900);
DISPLAY 0.638298 (-1589 3900);
PAINT MONO (-1589 3900);
FORCEPROP 2 LAST CDS_LIB standard
J 0
(-1775 3900);
DISPLAY INVISIBLE (-1775 3900);
FORCEPROP 1 LAST OFFPAGE TRUE
J 2
(-2100 3775);
DISPLAY 0.872340 (-2100 3775);
DISPLAY INVISIBLE (-2100 3775);
FORCEPROP 1 LAST COMMENT_BODY TRUE
J 2
(-1900 3800);
DISPLAY 0.872340 (-1900 3800);
PAINT GREEN (-1900 3800);
DISPLAY INVISIBLE (-1900 3800);
FORCEPROP 2 LAST PATH I145
J 0
(-1600 3975);
DISPLAY 0.680851 (-1600 3975);
DISPLAY INVISIBLE (-1600 3975);
FORCEADD Q_RES..1
R 2
(-2775 4050);
FORCEPROP 1 LAST LOCATION R6850
J 0
(-2975 4050);
DISPLAY 0.489362 (-2975 4050);
PAINT SKYBLUE (-2975 4050);
FORCEPROP 0 LAST $SEC 1
J 0
(-2650 4075);
DISPLAY 0.680851 (-2650 4075);
PAINT MONO (-2650 4075);
DISPLAY INVISIBLE (-2650 4075);
FORCEPROP 0 LAST CDS_SEC 1
J 0
(-2650 4075);
DISPLAY 0.680851 (-2650 4075);
DISPLAY INVISIBLE (-2650 4075);
FORCEPROP 1 LASTPIN (-2675 4050) $PN 1
J 2
(-2687 4062);
DISPLAY 0.787234 (-2687 4062);
PAINT MONO (-2687 4062);
FORCEPROP 1 LASTPIN (-2875 4050) $PN 2
J 2
(-2837 4062);
DISPLAY 0.787234 (-2837 4062);
PAINT MONO (-2837 4062);
FORCEPROP 1 LAST VALUE 33
J 0
(-2650 4050);
DISPLAY 0.489362 (-2650 4050);
PAINT SKYBLUE (-2650 4050);
FORCEPROP 2 LAST CDS_LIB pure_quanta
J 0
(-2775 4050);
DISPLAY INVISIBLE (-2775 4050);
FORCEPROP 2 LAST BOM_COST MEM
J 0
(-2800 4200);
DISPLAY 0.744681 (-2800 4200);
PAINT WHITE (-2800 4200);
DISPLAY INVISIBLE (-2800 4200);
FORCEPROP 1 LAST WATTAGE 1/16W
J 0
(-2700 3975);
DISPLAY 0.489362 (-2700 3975);
PAINT SKYBLUE (-2700 3975);
DISPLAY INVISIBLE (-2700 3975);
FORCEPROP 1 LAST MATERIAL CHIP
J 0
(-2950 4025);
DISPLAY 0.489362 (-2950 4025);
PAINT SKYBLUE (-2950 4025);
DISPLAY INVISIBLE (-2950 4025);
FORCEPROP 1 LAST TOLERANCE 5%
J 2
(-2650 4025);
DISPLAY 0.489362 (-2650 4025);
PAINT SKYBLUE (-2650 4025);
DISPLAY INVISIBLE (-2650 4025);
FORCEPROP 1 LAST PACK_TYPE 0402LF
J 0
(-2950 3975);
DISPLAY 0.489362 (-2950 3975);
PAINT SKYBLUE (-2950 3975);
DISPLAY INVISIBLE (-2950 3975);
FORCEPROP 1 LAST PATH I146
J 2
(-2725 4200);
DISPLAY 0.978723 (-2725 4200);
PAINT WHITE (-2725 4200);
DISPLAY INVISIBLE (-2725 4200);
FORCEPROP 1 LAST PART_NUMBER CS03302JB10
J 0
(-2875 4100);
DISPLAY 0.489362 (-2875 4100);
PAINT SKYBLUE (-2875 4100);
DISPLAY INVISIBLE (-2875 4100);
FORCEADD Q_RES..1
R 2
(-2775 3000);
FORCEPROP 1 LAST LOCATION R6851
J 0
(-2975 3000);
DISPLAY 0.489362 (-2975 3000);
PAINT SKYBLUE (-2975 3000);
FORCEPROP 0 LAST $SEC 1
J 0
(-2650 3025);
DISPLAY 0.680851 (-2650 3025);
PAINT MONO (-2650 3025);
DISPLAY INVISIBLE (-2650 3025);
FORCEPROP 0 LAST CDS_SEC 1
J 0
(-2650 3025);
DISPLAY 0.680851 (-2650 3025);
DISPLAY INVISIBLE (-2650 3025);
FORCEPROP 1 LASTPIN (-2675 3000) $PN 1
J 2
(-2687 3012);
DISPLAY 0.787234 (-2687 3012);
PAINT MONO (-2687 3012);
FORCEPROP 1 LASTPIN (-2875 3000) $PN 2
J 2
(-2837 3012);
DISPLAY 0.787234 (-2837 3012);
PAINT MONO (-2837 3012);
FORCEPROP 1 LAST VALUE 33
J 0
(-2650 3000);
DISPLAY 0.489362 (-2650 3000);
PAINT SKYBLUE (-2650 3000);
FORCEPROP 2 LAST BOM_COST MEM
J 0
(-2800 3150);
DISPLAY 0.744681 (-2800 3150);
PAINT WHITE (-2800 3150);
DISPLAY INVISIBLE (-2800 3150);
FORCEPROP 1 LAST WATTAGE 1/16W
J 0
(-2700 2925);
DISPLAY 0.489362 (-2700 2925);
PAINT SKYBLUE (-2700 2925);
DISPLAY INVISIBLE (-2700 2925);
FORCEPROP 1 LAST MATERIAL CHIP
J 0
(-2950 2975);
DISPLAY 0.489362 (-2950 2975);
PAINT SKYBLUE (-2950 2975);
DISPLAY INVISIBLE (-2950 2975);
FORCEPROP 1 LAST TOLERANCE 5%
J 2
(-2650 2975);
DISPLAY 0.489362 (-2650 2975);
PAINT SKYBLUE (-2650 2975);
DISPLAY INVISIBLE (-2650 2975);
FORCEPROP 1 LAST PACK_TYPE 0402LF
J 0
(-2950 2925);
DISPLAY 0.489362 (-2950 2925);
PAINT SKYBLUE (-2950 2925);
DISPLAY INVISIBLE (-2950 2925);
FORCEPROP 2 LAST CDS_LIB pure_quanta
J 0
(-2775 3000);
DISPLAY INVISIBLE (-2775 3000);
FORCEPROP 1 LAST PATH I147
J 2
(-2725 3150);
DISPLAY 0.978723 (-2725 3150);
PAINT WHITE (-2725 3150);
DISPLAY INVISIBLE (-2725 3150);
FORCEPROP 1 LAST PART_NUMBER CS03302JB10
J 0
(-2875 3050);
DISPLAY 0.489362 (-2875 3050);
PAINT SKYBLUE (-2875 3050);
DISPLAY INVISIBLE (-2875 3050);
FORCEADD OFFPAGE..2
(-1775 4050);
FORCEPROP 2 LAST $XR0 361 
J 0
(-1586 4050);
DISPLAY 0.638298 (-1586 4050);
PAINT MONO (-1586 4050);
FORCEPROP 2 LAST CDS_LIB standard
J 0
(-1775 4050);
DISPLAY INVISIBLE (-1775 4050);
FORCEPROP 1 LAST OFFPAGE TRUE
J 0
(-1450 3925);
DISPLAY 0.872340 (-1450 3925);
PAINT GREEN (-1450 3925);
DISPLAY INVISIBLE (-1450 3925);
FORCEPROP 1 LAST COMMENT_BODY TRUE
J 0
(-1820 3955);
DISPLAY 0.872340 (-1820 3955);
PAINT GREEN (-1820 3955);
DISPLAY INVISIBLE (-1820 3955);
FORCEPROP 2 LAST PATH I148
J 0
(-1600 4125);
DISPLAY 0.680851 (-1600 4125);
DISPLAY INVISIBLE (-1600 4125);
FORCEADD OFFPAGE..2
(-1775 3000);
FORCEPROP 2 LAST $XR0 362 
J 0
(-1586 3000);
DISPLAY 0.638298 (-1586 3000);
PAINT MONO (-1586 3000);
FORCEPROP 2 LAST CDS_LIB standard
J 0
(-1775 3000);
DISPLAY INVISIBLE (-1775 3000);
FORCEPROP 1 LAST OFFPAGE TRUE
J 0
(-1450 2875);
DISPLAY 0.872340 (-1450 2875);
DISPLAY INVISIBLE (-1450 2875);
FORCEPROP 1 LAST COMMENT_BODY TRUE
J 0
(-1820 2905);
DISPLAY 0.872340 (-1820 2905);
PAINT GREEN (-1820 2905);
DISPLAY INVISIBLE (-1820 2905);
FORCEPROP 2 LAST PATH I149
J 0
(-1600 3075);
DISPLAY 0.680851 (-1600 3075);
DISPLAY INVISIBLE (-1600 3075);
FORCEADD OFFPAGE..4
R 2
(-7875 4050);
FORCEPROP 2 LAST $XR1 151 
J 0
(-8247 4050);
DISPLAY 0.638298 (-8247 4050);
PAINT MONO (-8247 4050);
FORCEPROP 2 LAST $XR0 150 
J 0
(-8127 4050);
DISPLAY 0.638298 (-8127 4050);
PAINT MONO (-8127 4050);
FORCEPROP 2 LAST CDS_LIB standard
J 0
(-7875 4050);
DISPLAY INVISIBLE (-7875 4050);
FORCEPROP 1 LAST OFFPAGE TRUE
J 2
(-8200 3925);
DISPLAY 0.872340 (-8200 3925);
PAINT GREEN (-8200 3925);
DISPLAY INVISIBLE (-8200 3925);
FORCEPROP 1 LAST COMMENT_BODY TRUE
J 2
(-7850 3950);
DISPLAY 0.872340 (-7850 3950);
PAINT GREEN (-7850 3950);
DISPLAY INVISIBLE (-7850 3950);
FORCEPROP 2 LAST PATH I15
J 0
(-8125 4100);
DISPLAY 0.680851 (-8125 4100);
DISPLAY INVISIBLE (-8125 4100);
FORCEADD Q_RES..1
R 2
(-6850 3300);
FORCEPROP 1 LAST LOCATION R152
J 0
(-7075 3300);
DISPLAY 0.489362 (-7075 3300);
PAINT SKYBLUE (-7075 3300);
FORCEPROP 0 LAST $SEC 1
J 0
(-6725 3325);
DISPLAY 0.680851 (-6725 3325);
PAINT MONO (-6725 3325);
DISPLAY INVISIBLE (-6725 3325);
FORCEPROP 0 LAST CDS_SEC 1
J 0
(-6725 3325);
DISPLAY 0.680851 (-6725 3325);
DISPLAY INVISIBLE (-6725 3325);
FORCEPROP 1 LASTPIN (-6750 3300) $PN 1
J 2
(-6762 3312);
DISPLAY 0.787234 (-6762 3312);
PAINT MONO (-6762 3312);
FORCEPROP 1 LASTPIN (-6950 3300) $PN 2
J 2
(-6912 3312);
DISPLAY 0.787234 (-6912 3312);
PAINT MONO (-6912 3312);
FORCEPROP 1 LAST VALUE 33
J 0
(-6725 3300);
DISPLAY 0.489362 (-6725 3300);
PAINT SKYBLUE (-6725 3300);
FORCEPROP 1 LAST PACK_TYPE 0402LF
J 0
(-7025 3225);
DISPLAY 0.489362 (-7025 3225);
PAINT SKYBLUE (-7025 3225);
DISPLAY INVISIBLE (-7025 3225);
FORCEPROP 1 LAST TOLERANCE 5%
J 2
(-6725 3275);
DISPLAY 0.489362 (-6725 3275);
PAINT SKYBLUE (-6725 3275);
DISPLAY INVISIBLE (-6725 3275);
FORCEPROP 1 LAST MATERIAL CHIP
J 0
(-7025 3275);
DISPLAY 0.489362 (-7025 3275);
PAINT SKYBLUE (-7025 3275);
DISPLAY INVISIBLE (-7025 3275);
FORCEPROP 1 LAST WATTAGE 1/16W
J 0
(-6775 3225);
DISPLAY 0.489362 (-6775 3225);
PAINT SKYBLUE (-6775 3225);
DISPLAY INVISIBLE (-6775 3225);
FORCEPROP 2 LAST BOM_COST MEM
J 0
(-6875 3450);
DISPLAY 0.744681 (-6875 3450);
PAINT WHITE (-6875 3450);
DISPLAY INVISIBLE (-6875 3450);
FORCEPROP 2 LAST CDS_LIB pure_quanta
J 0
(-6850 3300);
DISPLAY INVISIBLE (-6850 3300);
FORCEPROP 1 LAST PATH I153
J 2
(-6800 3450);
DISPLAY 0.978723 (-6800 3450);
PAINT WHITE (-6800 3450);
DISPLAY INVISIBLE (-6800 3450);
FORCEPROP 1 LAST PART_NUMBER CS03302JB10
J 0
(-6950 3350);
DISPLAY 0.489362 (-6950 3350);
PAINT SKYBLUE (-6950 3350);
DISPLAY INVISIBLE (-6950 3350);
FORCEADD OFFPAGE..2
(-1750 3400);
FORCEPROP 2 LAST $XR0 142 
J 0
(-1561 3400);
DISPLAY 0.638298 (-1561 3400);
PAINT MONO (-1561 3400);
FORCEPROP 2 LAST CDS_LIB standard
J 0
(-1750 3400);
DISPLAY INVISIBLE (-1750 3400);
FORCEPROP 1 LAST OFFPAGE TRUE
J 0
(-1425 3275);
DISPLAY 0.872340 (-1425 3275);
PAINT GREEN (-1425 3275);
DISPLAY INVISIBLE (-1425 3275);
FORCEPROP 1 LAST COMMENT_BODY TRUE
J 0
(-1795 3305);
DISPLAY 0.872340 (-1795 3305);
PAINT GREEN (-1795 3305);
DISPLAY INVISIBLE (-1795 3305);
FORCEPROP 2 LAST PATH I154
J 0
(-1300 3450);
DISPLAY 0.680851 (-1300 3450);
DISPLAY INVISIBLE (-1300 3450);
FORCEADD Q_RES..1
R 2
(-2675 3400);
FORCEPROP 1 LAST LOCATION R1179
J 0
(-2875 3400);
DISPLAY 0.489362 (-2875 3400);
PAINT SKYBLUE (-2875 3400);
FORCEPROP 0 LAST $SEC 1
J 0
(-2550 3425);
DISPLAY 0.680851 (-2550 3425);
PAINT MONO (-2550 3425);
DISPLAY INVISIBLE (-2550 3425);
FORCEPROP 0 LAST CDS_SEC 1
J 0
(-2550 3425);
DISPLAY 0.680851 (-2550 3425);
DISPLAY INVISIBLE (-2550 3425);
FORCEPROP 1 LASTPIN (-2575 3400) $PN 1
J 2
(-2587 3412);
DISPLAY 0.787234 (-2587 3412);
PAINT MONO (-2587 3412);
FORCEPROP 1 LASTPIN (-2775 3400) $PN 2
J 2
(-2737 3412);
DISPLAY 0.787234 (-2737 3412);
PAINT MONO (-2737 3412);
FORCEPROP 1 LAST VALUE 0
J 0
(-2550 3400);
DISPLAY 0.489362 (-2550 3400);
PAINT SKYBLUE (-2550 3400);
FORCEPROP 2 LAST BOM_COST MEM
J 0
(-2700 3550);
DISPLAY 0.744681 (-2700 3550);
PAINT WHITE (-2700 3550);
DISPLAY INVISIBLE (-2700 3550);
FORCEPROP 1 LAST WATTAGE 1/16W
J 0
(-2600 3325);
DISPLAY 0.489362 (-2600 3325);
PAINT SKYBLUE (-2600 3325);
DISPLAY INVISIBLE (-2600 3325);
FORCEPROP 1 LAST MATERIAL CHIP
J 0
(-2850 3375);
DISPLAY 0.489362 (-2850 3375);
PAINT SKYBLUE (-2850 3375);
DISPLAY INVISIBLE (-2850 3375);
FORCEPROP 1 LAST TOLERANCE 5%
J 2
(-2550 3375);
DISPLAY 0.489362 (-2550 3375);
PAINT SKYBLUE (-2550 3375);
DISPLAY INVISIBLE (-2550 3375);
FORCEPROP 1 LAST PACK_TYPE 0402LF
J 0
(-2850 3325);
DISPLAY 0.489362 (-2850 3325);
PAINT SKYBLUE (-2850 3325);
DISPLAY INVISIBLE (-2850 3325);
FORCEPROP 2 LAST CDS_LIB pure_quanta
J 0
(-2675 3400);
DISPLAY INVISIBLE (-2675 3400);
FORCEPROP 1 LAST PATH I155
J 2
(-2625 3550);
DISPLAY 0.978723 (-2625 3550);
PAINT WHITE (-2625 3550);
DISPLAY INVISIBLE (-2625 3550);
FORCEPROP 1 LAST PART_NUMBER CS00002JB13
J 0
(-2775 3450);
DISPLAY 0.489362 (-2775 3450);
PAINT SKYBLUE (-2775 3450);
DISPLAY INVISIBLE (-2775 3450);
FORCEADD Q_RES..1
R 2
(-6850 2700);
FORCEPROP 1 LAST LOCATION R160
J 0
(-7100 2700);
DISPLAY 0.489362 (-7100 2700);
PAINT SKYBLUE (-7100 2700);
FORCEPROP 0 LAST $SEC 1
J 0
(-6975 2750);
DISPLAY 0.680851 (-6975 2750);
PAINT MONO (-6975 2750);
DISPLAY INVISIBLE (-6975 2750);
FORCEPROP 0 LAST CDS_SEC 1
J 0
(-6975 2750);
DISPLAY 1.021277 (-6975 2750);
DISPLAY INVISIBLE (-6975 2750);
FORCEPROP 1 LASTPIN (-6750 2700) $PN 1
J 2
(-6762 2712);
DISPLAY 0.489362 (-6762 2712);
PAINT MONO (-6762 2712);
FORCEPROP 1 LASTPIN (-6950 2700) $PN 2
J 2
(-6912 2712);
DISPLAY 0.489362 (-6912 2712);
PAINT MONO (-6912 2712);
FORCEPROP 1 LAST VALUE 33
J 0
(-6725 2700);
DISPLAY 0.489362 (-6725 2700);
PAINT SKYBLUE (-6725 2700);
FORCEPROP 1 LAST PACK_TYPE 0402LF
J 0
(-7025 2625);
DISPLAY 0.489362 (-7025 2625);
PAINT SKYBLUE (-7025 2625);
DISPLAY INVISIBLE (-7025 2625);
FORCEPROP 1 LAST TOLERANCE 5%
J 2
(-6725 2675);
DISPLAY 0.489362 (-6725 2675);
PAINT SKYBLUE (-6725 2675);
DISPLAY INVISIBLE (-6725 2675);
FORCEPROP 1 LAST MATERIAL CHIP
J 0
(-7025 2675);
DISPLAY 0.489362 (-7025 2675);
PAINT SKYBLUE (-7025 2675);
DISPLAY INVISIBLE (-7025 2675);
FORCEPROP 1 LAST WATTAGE 1/16W
J 0
(-6775 2625);
DISPLAY 0.489362 (-6775 2625);
PAINT SKYBLUE (-6775 2625);
DISPLAY INVISIBLE (-6775 2625);
FORCEPROP 2 LAST BOM_COST MEM
J 0
(-6875 2850);
DISPLAY 0.744681 (-6875 2850);
PAINT WHITE (-6875 2850);
DISPLAY INVISIBLE (-6875 2850);
FORCEPROP 2 LAST CDS_LIB pure_quanta
J 0
(-6850 2700);
DISPLAY INVISIBLE (-6850 2700);
FORCEPROP 1 LAST PATH I16
J 2
(-6800 2850);
DISPLAY 0.978723 (-6800 2850);
PAINT WHITE (-6800 2850);
DISPLAY INVISIBLE (-6800 2850);
FORCEPROP 1 LAST PART_NUMBER CS03302JB10
J 0
(-6950 2750);
DISPLAY 0.489362 (-6950 2750);
PAINT SKYBLUE (-6950 2750);
DISPLAY INVISIBLE (-6950 2750);
FORCEADD Q_RES..1
R 2
(-6850 2750);
FORCEPROP 1 LAST LOCATION R992
J 0
(-7100 2750);
DISPLAY 0.489362 (-7100 2750);
PAINT SKYBLUE (-7100 2750);
FORCEPROP 0 LAST $SEC 1
J 0
(-6975 2800);
DISPLAY 0.680851 (-6975 2800);
PAINT MONO (-6975 2800);
DISPLAY INVISIBLE (-6975 2800);
FORCEPROP 0 LAST CDS_SEC 1
J 0
(-6975 2800);
DISPLAY 0.680851 (-6975 2800);
DISPLAY INVISIBLE (-6975 2800);
FORCEPROP 1 LASTPIN (-6750 2750) $PN 1
J 2
(-6762 2762);
DISPLAY 0.489362 (-6762 2762);
PAINT MONO (-6762 2762);
FORCEPROP 1 LASTPIN (-6950 2750) $PN 2
J 2
(-6912 2762);
DISPLAY 0.489362 (-6912 2762);
PAINT MONO (-6912 2762);
FORCEPROP 1 LAST VALUE 33
J 0
(-6725 2750);
DISPLAY 0.489362 (-6725 2750);
PAINT SKYBLUE (-6725 2750);
FORCEPROP 1 LAST PACK_TYPE 0402LF
J 0
(-7025 2675);
DISPLAY 0.489362 (-7025 2675);
PAINT SKYBLUE (-7025 2675);
DISPLAY INVISIBLE (-7025 2675);
FORCEPROP 1 LAST TOLERANCE 5%
J 2
(-6725 2725);
DISPLAY 0.489362 (-6725 2725);
PAINT SKYBLUE (-6725 2725);
DISPLAY INVISIBLE (-6725 2725);
FORCEPROP 1 LAST MATERIAL CHIP
J 0
(-7025 2725);
DISPLAY 0.489362 (-7025 2725);
PAINT SKYBLUE (-7025 2725);
DISPLAY INVISIBLE (-7025 2725);
FORCEPROP 1 LAST WATTAGE 1/16W
J 0
(-6775 2675);
DISPLAY 0.489362 (-6775 2675);
PAINT SKYBLUE (-6775 2675);
DISPLAY INVISIBLE (-6775 2675);
FORCEPROP 2 LAST CDS_LIB pure_quanta
J 0
(-6850 2750);
DISPLAY INVISIBLE (-6850 2750);
FORCEPROP 2 LAST BOM_COST MEM
J 0
(-6875 2900);
DISPLAY 0.744681 (-6875 2900);
PAINT WHITE (-6875 2900);
DISPLAY INVISIBLE (-6875 2900);
FORCEPROP 1 LAST PATH I17
J 2
(-6800 2900);
DISPLAY 0.978723 (-6800 2900);
PAINT WHITE (-6800 2900);
DISPLAY INVISIBLE (-6800 2900);
FORCEPROP 1 LAST PART_NUMBER CS03302JB10
J 0
(-6950 2800);
DISPLAY 0.489362 (-6950 2800);
PAINT SKYBLUE (-6950 2800);
DISPLAY INVISIBLE (-6950 2800);
FORCEADD Q_RES..1
R 2
(-6850 2950);
FORCEPROP 1 LAST LOCATION R493
J 0
(-7100 2950);
DISPLAY 0.489362 (-7100 2950);
PAINT SKYBLUE (-7100 2950);
FORCEPROP 0 LAST $SEC 1
J 0
(-6900 3000);
DISPLAY 0.680851 (-6900 3000);
PAINT MONO (-6900 3000);
DISPLAY INVISIBLE (-6900 3000);
FORCEPROP 0 LAST CDS_SEC 1
J 0
(-6900 3000);
DISPLAY 1.021277 (-6900 3000);
DISPLAY INVISIBLE (-6900 3000);
FORCEPROP 1 LASTPIN (-6750 2950) $PN 1
J 2
(-6762 2962);
DISPLAY 0.489362 (-6762 2962);
PAINT MONO (-6762 2962);
FORCEPROP 1 LASTPIN (-6950 2950) $PN 2
J 2
(-6935 2960);
DISPLAY 0.489362 (-6935 2960);
PAINT MONO (-6935 2960);
FORCEPROP 1 LAST VALUE 0
J 0
(-6725 2950);
DISPLAY 0.489362 (-6725 2950);
PAINT SKYBLUE (-6725 2950);
FORCEPROP 1 LAST PACK_TYPE 0402LF
J 0
(-7025 2875);
DISPLAY 0.489362 (-7025 2875);
PAINT SKYBLUE (-7025 2875);
DISPLAY INVISIBLE (-7025 2875);
FORCEPROP 1 LAST TOLERANCE 5%
J 2
(-6725 2925);
DISPLAY 0.489362 (-6725 2925);
PAINT SKYBLUE (-6725 2925);
DISPLAY INVISIBLE (-6725 2925);
FORCEPROP 1 LAST MATERIAL CHIP
J 0
(-7025 2925);
DISPLAY 0.489362 (-7025 2925);
PAINT SKYBLUE (-7025 2925);
DISPLAY INVISIBLE (-7025 2925);
FORCEPROP 1 LAST WATTAGE 1/16W
J 0
(-6775 2875);
DISPLAY 0.489362 (-6775 2875);
PAINT SKYBLUE (-6775 2875);
DISPLAY INVISIBLE (-6775 2875);
FORCEPROP 2 LAST BOM_COST MEM
J 0
(-6875 3100);
DISPLAY 0.744681 (-6875 3100);
PAINT WHITE (-6875 3100);
DISPLAY INVISIBLE (-6875 3100);
FORCEPROP 2 LAST CDS_LIB pure_quanta
J 0
(-6850 2950);
DISPLAY INVISIBLE (-6850 2950);
FORCEPROP 1 LAST PATH I18
J 2
(-6800 3100);
DISPLAY 0.978723 (-6800 3100);
PAINT WHITE (-6800 3100);
DISPLAY INVISIBLE (-6800 3100);
FORCEPROP 1 LAST PART_NUMBER CS00002JB13
J 0
(-6950 3000);
DISPLAY 0.489362 (-6950 3000);
PAINT SKYBLUE (-6950 3000);
DISPLAY INVISIBLE (-6950 3000);
FORCEADD Q_RES..1
R 2
(-6850 3000);
FORCEPROP 1 LAST LOCATION R70
J 0
(-7100 3000);
DISPLAY 0.489362 (-7100 3000);
PAINT SKYBLUE (-7100 3000);
FORCEPROP 0 LAST $SEC 1
J 0
(-6900 3050);
DISPLAY 0.680851 (-6900 3050);
PAINT MONO (-6900 3050);
DISPLAY INVISIBLE (-6900 3050);
FORCEPROP 0 LAST CDS_SEC 1
J 0
(-6900 3050);
DISPLAY 1.021277 (-6900 3050);
DISPLAY INVISIBLE (-6900 3050);
FORCEPROP 1 LASTPIN (-6750 3000) $PN 1
J 2
(-6762 3012);
DISPLAY 0.489362 (-6762 3012);
PAINT MONO (-6762 3012);
FORCEPROP 1 LASTPIN (-6950 3000) $PN 2
J 2
(-6935 3010);
DISPLAY 0.489362 (-6935 3010);
PAINT MONO (-6935 3010);
FORCEPROP 1 LAST VALUE 0
J 0
(-6725 3000);
DISPLAY 0.489362 (-6725 3000);
PAINT SKYBLUE (-6725 3000);
FORCEPROP 1 LAST PACK_TYPE 0402LF
J 0
(-7025 2925);
DISPLAY 0.489362 (-7025 2925);
PAINT SKYBLUE (-7025 2925);
DISPLAY INVISIBLE (-7025 2925);
FORCEPROP 1 LAST TOLERANCE 5%
J 2
(-6725 2975);
DISPLAY 0.489362 (-6725 2975);
PAINT SKYBLUE (-6725 2975);
DISPLAY INVISIBLE (-6725 2975);
FORCEPROP 1 LAST MATERIAL CHIP
J 0
(-7025 2975);
DISPLAY 0.489362 (-7025 2975);
PAINT SKYBLUE (-7025 2975);
DISPLAY INVISIBLE (-7025 2975);
FORCEPROP 1 LAST WATTAGE 1/16W
J 0
(-6775 2925);
DISPLAY 0.489362 (-6775 2925);
PAINT SKYBLUE (-6775 2925);
DISPLAY INVISIBLE (-6775 2925);
FORCEPROP 2 LAST CDS_LIB pure_quanta
J 0
(-6850 3000);
DISPLAY INVISIBLE (-6850 3000);
FORCEPROP 2 LAST BOM_COST MEM
J 0
(-6875 3150);
DISPLAY 0.744681 (-6875 3150);
PAINT WHITE (-6875 3150);
DISPLAY INVISIBLE (-6875 3150);
FORCEPROP 1 LAST PATH I19
J 2
(-6800 3150);
DISPLAY 0.978723 (-6800 3150);
PAINT WHITE (-6800 3150);
DISPLAY INVISIBLE (-6800 3150);
FORCEPROP 1 LAST PART_NUMBER CS00002JB13
J 0
(-6950 3050);
DISPLAY 0.489362 (-6950 3050);
PAINT SKYBLUE (-6950 3050);
DISPLAY INVISIBLE (-6950 3050);
FORCEADD OFFPAGE..2
R 2
(-7875 2700);
FORCEPROP 2 LAST $XR0 172 
J 0
(-8130 2700);
DISPLAY 0.638298 (-8130 2700);
PAINT MONO (-8130 2700);
FORCEPROP 2 LAST CDS_LIB standard
J 0
(-7875 2700);
DISPLAY INVISIBLE (-7875 2700);
FORCEPROP 1 LAST OFFPAGE TRUE
J 2
(-8200 2575);
DISPLAY 0.872340 (-8200 2575);
PAINT GREEN (-8200 2575);
DISPLAY INVISIBLE (-8200 2575);
FORCEPROP 1 LAST COMMENT_BODY TRUE
J 2
(-7830 2605);
DISPLAY 0.872340 (-7830 2605);
PAINT GREEN (-7830 2605);
DISPLAY INVISIBLE (-7830 2605);
FORCEPROP 2 LAST PATH I2
J 0
(-8150 2750);
DISPLAY 0.680851 (-8150 2750);
DISPLAY INVISIBLE (-8150 2750);
FORCEADD Q_RES..1
R 2
(-6850 3050);
FORCEPROP 1 LAST LOCATION R6039
J 0
(-7100 3050);
DISPLAY 0.489362 (-7100 3050);
PAINT SKYBLUE (-7100 3050);
FORCEPROP 0 LAST $SEC 1
J 0
(-6900 3100);
DISPLAY 0.680851 (-6900 3100);
PAINT MONO (-6900 3100);
DISPLAY INVISIBLE (-6900 3100);
FORCEPROP 0 LAST CDS_SEC 1
J 0
(-6900 3100);
DISPLAY 1.021277 (-6900 3100);
DISPLAY INVISIBLE (-6900 3100);
FORCEPROP 1 LASTPIN (-6750 3050) $PN 1
J 2
(-6762 3062);
DISPLAY 0.489362 (-6762 3062);
PAINT MONO (-6762 3062);
FORCEPROP 1 LASTPIN (-6950 3050) $PN 2
J 2
(-6935 3060);
DISPLAY 0.489362 (-6935 3060);
PAINT MONO (-6935 3060);
FORCEPROP 1 LAST VALUE 0
J 0
(-6725 3050);
DISPLAY 0.489362 (-6725 3050);
PAINT SKYBLUE (-6725 3050);
FORCEPROP 1 LAST PACK_TYPE 0402LF
J 0
(-7025 2975);
DISPLAY 0.489362 (-7025 2975);
PAINT SKYBLUE (-7025 2975);
DISPLAY INVISIBLE (-7025 2975);
FORCEPROP 1 LAST TOLERANCE 5%
J 2
(-6725 3025);
DISPLAY 0.489362 (-6725 3025);
PAINT SKYBLUE (-6725 3025);
DISPLAY INVISIBLE (-6725 3025);
FORCEPROP 1 LAST MATERIAL CHIP
J 0
(-7025 3025);
DISPLAY 0.489362 (-7025 3025);
PAINT SKYBLUE (-7025 3025);
DISPLAY INVISIBLE (-7025 3025);
FORCEPROP 1 LAST WATTAGE 1/16W
J 0
(-6775 2975);
DISPLAY 0.489362 (-6775 2975);
PAINT SKYBLUE (-6775 2975);
DISPLAY INVISIBLE (-6775 2975);
FORCEPROP 2 LAST CDS_LIB pure_quanta
J 0
(-6850 3050);
DISPLAY INVISIBLE (-6850 3050);
FORCEPROP 2 LAST BOM_COST MEM
J 0
(-6875 3200);
DISPLAY 0.744681 (-6875 3200);
PAINT WHITE (-6875 3200);
DISPLAY INVISIBLE (-6875 3200);
FORCEPROP 1 LAST PATH I20
J 2
(-6800 3200);
DISPLAY 0.978723 (-6800 3200);
PAINT WHITE (-6800 3200);
DISPLAY INVISIBLE (-6800 3200);
FORCEPROP 1 LAST PART_NUMBER CS00002JB13
J 0
(-6950 3100);
DISPLAY 0.489362 (-6950 3100);
PAINT SKYBLUE (-6950 3100);
DISPLAY INVISIBLE (-6950 3100);
FORCEADD Q_RES..1
R 2
(-6850 3100);
FORCEPROP 1 LAST LOCATION R6038
J 0
(-7100 3100);
DISPLAY 0.489362 (-7100 3100);
PAINT SKYBLUE (-7100 3100);
FORCEPROP 0 LAST $SEC 1
J 0
(-6900 3150);
DISPLAY 0.680851 (-6900 3150);
PAINT MONO (-6900 3150);
DISPLAY INVISIBLE (-6900 3150);
FORCEPROP 0 LAST CDS_SEC 1
J 0
(-6900 3150);
DISPLAY 1.021277 (-6900 3150);
DISPLAY INVISIBLE (-6900 3150);
FORCEPROP 1 LASTPIN (-6750 3100) $PN 1
J 2
(-6762 3112);
DISPLAY 0.489362 (-6762 3112);
PAINT MONO (-6762 3112);
FORCEPROP 1 LASTPIN (-6950 3100) $PN 2
J 2
(-6935 3110);
DISPLAY 0.489362 (-6935 3110);
PAINT MONO (-6935 3110);
FORCEPROP 1 LAST VALUE 0
J 0
(-6725 3100);
DISPLAY 0.489362 (-6725 3100);
PAINT SKYBLUE (-6725 3100);
FORCEPROP 2 LAST BOM_COST MEM
J 0
(-6875 3250);
DISPLAY 0.744681 (-6875 3250);
PAINT WHITE (-6875 3250);
DISPLAY INVISIBLE (-6875 3250);
FORCEPROP 2 LAST CDS_LIB pure_quanta
J 0
(-6850 3100);
DISPLAY INVISIBLE (-6850 3100);
FORCEPROP 1 LAST WATTAGE 1/16W
J 0
(-6775 3025);
DISPLAY 0.489362 (-6775 3025);
PAINT SKYBLUE (-6775 3025);
DISPLAY INVISIBLE (-6775 3025);
FORCEPROP 1 LAST MATERIAL CHIP
J 0
(-7025 3075);
DISPLAY 0.489362 (-7025 3075);
PAINT SKYBLUE (-7025 3075);
DISPLAY INVISIBLE (-7025 3075);
FORCEPROP 1 LAST TOLERANCE 5%
J 2
(-6725 3075);
DISPLAY 0.489362 (-6725 3075);
PAINT SKYBLUE (-6725 3075);
DISPLAY INVISIBLE (-6725 3075);
FORCEPROP 1 LAST PACK_TYPE 0402LF
J 0
(-7025 3025);
DISPLAY 0.489362 (-7025 3025);
PAINT SKYBLUE (-7025 3025);
DISPLAY INVISIBLE (-7025 3025);
FORCEPROP 1 LAST PATH I21
J 2
(-6800 3250);
DISPLAY 0.978723 (-6800 3250);
PAINT WHITE (-6800 3250);
DISPLAY INVISIBLE (-6800 3250);
FORCEPROP 1 LAST PART_NUMBER CS00002JB13
J 0
(-6950 3150);
DISPLAY 0.489362 (-6950 3150);
PAINT SKYBLUE (-6950 3150);
DISPLAY INVISIBLE (-6950 3150);
FORCEADD Q_RES..1
R 2
(-6850 3400);
FORCEPROP 1 LAST LOCATION R23
J 0
(-7075 3400);
DISPLAY 0.489362 (-7075 3400);
PAINT SKYBLUE (-7075 3400);
FORCEPROP 0 LAST $SEC 1
J 0
(-7075 3450);
DISPLAY 0.680851 (-7075 3450);
PAINT MONO (-7075 3450);
DISPLAY INVISIBLE (-7075 3450);
FORCEPROP 0 LAST CDS_SEC 1
J 0
(-7075 3450);
DISPLAY 0.680851 (-7075 3450);
DISPLAY INVISIBLE (-7075 3450);
FORCEPROP 1 LASTPIN (-6750 3400) $PN 1
J 2
(-6762 3412);
DISPLAY 0.489362 (-6762 3412);
PAINT MONO (-6762 3412);
FORCEPROP 1 LASTPIN (-6950 3400) $PN 2
J 2
(-6912 3412);
DISPLAY 0.489362 (-6912 3412);
PAINT MONO (-6912 3412);
FORCEPROP 1 LAST VALUE 33
J 0
(-6725 3400);
DISPLAY 0.489362 (-6725 3400);
PAINT SKYBLUE (-6725 3400);
FORCEPROP 2 LAST CDS_LIB pure_quanta
J 0
(-6850 3400);
DISPLAY INVISIBLE (-6850 3400);
FORCEPROP 1 LAST PACK_TYPE 0402LF
J 0
(-7025 3325);
DISPLAY 0.489362 (-7025 3325);
PAINT SKYBLUE (-7025 3325);
DISPLAY INVISIBLE (-7025 3325);
FORCEPROP 1 LAST TOLERANCE 5%
J 2
(-6725 3375);
DISPLAY 0.489362 (-6725 3375);
PAINT SKYBLUE (-6725 3375);
DISPLAY INVISIBLE (-6725 3375);
FORCEPROP 1 LAST MATERIAL CHIP
J 0
(-7025 3375);
DISPLAY 0.489362 (-7025 3375);
PAINT SKYBLUE (-7025 3375);
DISPLAY INVISIBLE (-7025 3375);
FORCEPROP 1 LAST WATTAGE 1/16W
J 0
(-6775 3325);
DISPLAY 0.489362 (-6775 3325);
PAINT SKYBLUE (-6775 3325);
DISPLAY INVISIBLE (-6775 3325);
FORCEPROP 2 LAST BOM_COST MEM
J 0
(-6875 3550);
DISPLAY 0.744681 (-6875 3550);
PAINT WHITE (-6875 3550);
DISPLAY INVISIBLE (-6875 3550);
FORCEPROP 1 LAST PATH I23
J 2
(-6800 3550);
DISPLAY 0.978723 (-6800 3550);
PAINT WHITE (-6800 3550);
DISPLAY INVISIBLE (-6800 3550);
FORCEPROP 1 LAST PART_NUMBER CS03302JB10
J 0
(-6950 3450);
DISPLAY 0.489362 (-6950 3450);
PAINT SKYBLUE (-6950 3450);
DISPLAY INVISIBLE (-6950 3450);
FORCEADD Q_RES..1
R 2
(-6825 3900);
FORCEPROP 1 LAST LOCATION R168
J 0
(-7050 3900);
DISPLAY 0.489362 (-7050 3900);
PAINT SKYBLUE (-7050 3900);
FORCEPROP 0 LAST $SEC 1
J 0
(-6925 3950);
DISPLAY 0.680851 (-6925 3950);
PAINT MONO (-6925 3950);
DISPLAY INVISIBLE (-6925 3950);
FORCEPROP 0 LAST CDS_SEC 1
J 0
(-6925 3950);
DISPLAY 1.021277 (-6925 3950);
DISPLAY INVISIBLE (-6925 3950);
FORCEPROP 1 LASTPIN (-6725 3900) $PN 1
J 2
(-6737 3912);
DISPLAY 0.489362 (-6737 3912);
PAINT MONO (-6737 3912);
FORCEPROP 1 LASTPIN (-6925 3900) $PN 2
J 2
(-6887 3912);
DISPLAY 0.489362 (-6887 3912);
PAINT MONO (-6887 3912);
FORCEPROP 1 LAST VALUE 0
J 0
(-6700 3900);
DISPLAY 0.489362 (-6700 3900);
PAINT SKYBLUE (-6700 3900);
FORCEPROP 2 LAST BOM_COST MEM
J 0
(-6850 4050);
DISPLAY 0.744681 (-6850 4050);
PAINT WHITE (-6850 4050);
DISPLAY INVISIBLE (-6850 4050);
FORCEPROP 2 LAST CDS_LIB pure_quanta
J 0
(-6825 3900);
DISPLAY INVISIBLE (-6825 3900);
FORCEPROP 1 LAST WATTAGE 1/16W
J 0
(-6750 3825);
DISPLAY 0.489362 (-6750 3825);
PAINT SKYBLUE (-6750 3825);
DISPLAY INVISIBLE (-6750 3825);
FORCEPROP 1 LAST MATERIAL CHIP
J 0
(-7000 3875);
DISPLAY 0.489362 (-7000 3875);
PAINT SKYBLUE (-7000 3875);
DISPLAY INVISIBLE (-7000 3875);
FORCEPROP 1 LAST TOLERANCE 5%
J 2
(-6700 3875);
DISPLAY 0.489362 (-6700 3875);
PAINT SKYBLUE (-6700 3875);
DISPLAY INVISIBLE (-6700 3875);
FORCEPROP 1 LAST PACK_TYPE 0402LF
J 0
(-7000 3825);
DISPLAY 0.489362 (-7000 3825);
PAINT SKYBLUE (-7000 3825);
DISPLAY INVISIBLE (-7000 3825);
FORCEPROP 1 LAST PATH I24
J 2
(-6775 4050);
DISPLAY 0.978723 (-6775 4050);
PAINT WHITE (-6775 4050);
DISPLAY INVISIBLE (-6775 4050);
FORCEPROP 1 LAST PART_NUMBER CS00002JB13
J 0
(-6925 3950);
DISPLAY 0.489362 (-6925 3950);
PAINT SKYBLUE (-6925 3950);
DISPLAY INVISIBLE (-6925 3950);
FORCEADD LCMXO3LF9400C5BG484C..4
(-5375 1250);
FORCEPROP 1 LAST LOCATION U18
J 0
(-5775 1675);
DISPLAY 0.723404 (-5775 1675);
PAINT GREEN (-5775 1675);
FORCEPROP 0 LAST $SEC 4
J 0
(-5775 1825);
DISPLAY 0.680851 (-5775 1825);
PAINT MONO (-5775 1825);
DISPLAY INVISIBLE (-5775 1825);
FORCEPROP 0 LAST CDS_SEC 4
J 0
(-5750 1900);
DISPLAY 0.680851 (-5750 1900);
DISPLAY INVISIBLE (-5750 1900);
FORCEPROP 0 LASTPIN (-4825 1450) $PN E8
J 0
(-4815 1460);
DISPLAY 0.680851 (-4815 1460);
PAINT MONO (-4815 1460);
FORCEPROP 0 LASTPIN (-4825 1400) $PN E9
J 0
(-4815 1410);
DISPLAY 0.680851 (-4815 1410);
PAINT MONO (-4815 1410);
FORCEPROP 0 LASTPIN (-4825 1350) $PN D10
J 0
(-4815 1360);
DISPLAY 0.680851 (-4815 1360);
PAINT MONO (-4815 1360);
FORCEPROP 0 LASTPIN (-4825 1300) $PN C10
J 0
(-4815 1310);
DISPLAY 0.680851 (-4815 1310);
PAINT MONO (-4815 1310);
FORCEPROP 0 LASTPIN (-4825 1250) $PN E14
J 0
(-4815 1260);
DISPLAY 0.680851 (-4815 1260);
PAINT MONO (-4815 1260);
FORCEPROP 0 LASTPIN (-4825 1200) $PN E15
J 0
(-4815 1210);
DISPLAY 0.680851 (-4815 1210);
PAINT MONO (-4815 1210);
FORCEPROP 0 LASTPIN (-4825 1150) $PN F16
J 0
(-4815 1160);
DISPLAY 0.680851 (-4815 1160);
PAINT MONO (-4815 1160);
FORCEPROP 0 LASTPIN (-4825 1100) $PN E17
J 0
(-4815 1110);
DISPLAY 0.680851 (-4815 1110);
PAINT MONO (-4815 1110);
FORCEPROP 2 LAST PART_TYPE SMLF
J 0
(-5775 1775);
DISPLAY 0.680851 (-5775 1775);
FORCEPROP 1 LAST MATERIAL IC
J 0
(-5772 1511);
DISPLAY 0.723404 (-5772 1511);
PAINT GREEN (-5772 1511);
FORCEPROP 2 LAST VALUE LCMXO3LF-9400C-5BG484C
J 0
(-5775 1725);
DISPLAY 0.489362 (-5775 1725);
PAINT SKYBLUE (-5775 1725);
FORCEPROP 2 LAST CDS_LIB pure_quanta
J 0
(-5375 1250);
DISPLAY INVISIBLE (-5375 1250);
FORCEPROP 1 LAST NEEDS_NO_SIZE TRUE
J 0
(-5375 1250);
DISPLAY 0.723404 (-5375 1250);
PAINT GREEN (-5375 1250);
DISPLAY INVISIBLE (-5375 1250);
FORCEPROP 1 LAST CDS_LMAN_SYM_OUTLINE -400,250,400,-250
J 0
(-5375 1250);
DISPLAY 0.468085 (-5375 1250);
PAINT GREEN (-5375 1250);
DISPLAY INVISIBLE (-5375 1250);
FORCEPROP 1 LAST PATH I25
J 0
(-5375 1250);
DISPLAY 0.723404 (-5375 1250);
PAINT GREEN (-5375 1250);
DISPLAY INVISIBLE (-5375 1250);
FORCEPROP 1 LAST PART_NUMBER AJ094000T08
J 0
(-5775 1638);
DISPLAY 0.723404 (-5775 1638);
PAINT GREEN (-5775 1638);
DISPLAY INVISIBLE (-5775 1638);
FORCEADD OFFPAGE..4
R 2
(-7875 4100);
FORCEPROP 2 LAST $XR1 151 
J 0
(-8247 4100);
DISPLAY 0.638298 (-8247 4100);
PAINT MONO (-8247 4100);
FORCEPROP 2 LAST $XR0 150 
J 0
(-8127 4100);
DISPLAY 0.638298 (-8127 4100);
PAINT MONO (-8127 4100);
FORCEPROP 2 LAST CDS_LIB standard
J 0
(-7875 4100);
DISPLAY INVISIBLE (-7875 4100);
FORCEPROP 1 LAST OFFPAGE TRUE
J 2
(-8200 3975);
DISPLAY 0.872340 (-8200 3975);
PAINT GREEN (-8200 3975);
DISPLAY INVISIBLE (-8200 3975);
FORCEPROP 1 LAST COMMENT_BODY TRUE
J 2
(-7850 4000);
DISPLAY 0.872340 (-7850 4000);
PAINT GREEN (-7850 4000);
DISPLAY INVISIBLE (-7850 4000);
FORCEPROP 2 LAST PATH I26
J 0
(-8125 4150);
DISPLAY 0.680851 (-8125 4150);
DISPLAY INVISIBLE (-8125 4150);
FORCEADD OFFPAGE..2
R 2
(-7875 4300);
FORCEPROP 2 LAST $XR0 159 
J 0
(-8130 4300);
DISPLAY 0.638298 (-8130 4300);
PAINT MONO (-8130 4300);
FORCEPROP 2 LAST CDS_LIB standard
J 0
(-7875 4300);
DISPLAY INVISIBLE (-7875 4300);
FORCEPROP 1 LAST OFFPAGE TRUE
J 2
(-8200 4175);
DISPLAY 0.872340 (-8200 4175);
PAINT GREEN (-8200 4175);
DISPLAY INVISIBLE (-8200 4175);
FORCEPROP 1 LAST COMMENT_BODY TRUE
J 2
(-7830 4205);
DISPLAY 0.872340 (-7830 4205);
PAINT GREEN (-7830 4205);
DISPLAY INVISIBLE (-7830 4205);
FORCEPROP 2 LAST PATH I27
J 0
(-8150 4350);
DISPLAY 0.680851 (-8150 4350);
DISPLAY INVISIBLE (-8150 4350);
FORCEADD OFFPAGE..4
R 2
(-7875 4200);
FORCEPROP 2 LAST $XR1 151 
J 0
(-8247 4200);
DISPLAY 0.638298 (-8247 4200);
PAINT MONO (-8247 4200);
FORCEPROP 2 LAST $XR0 150 
J 0
(-8127 4200);
DISPLAY 0.638298 (-8127 4200);
PAINT MONO (-8127 4200);
FORCEPROP 2 LAST CDS_LIB standard
J 0
(-7875 4200);
DISPLAY INVISIBLE (-7875 4200);
FORCEPROP 1 LAST OFFPAGE TRUE
J 2
(-8200 4075);
DISPLAY 0.872340 (-8200 4075);
PAINT GREEN (-8200 4075);
DISPLAY INVISIBLE (-8200 4075);
FORCEPROP 1 LAST COMMENT_BODY TRUE
J 2
(-7850 4100);
DISPLAY 0.872340 (-7850 4100);
PAINT GREEN (-7850 4100);
DISPLAY INVISIBLE (-7850 4100);
FORCEPROP 2 LAST PATH I28
J 0
(-8125 4250);
DISPLAY 0.680851 (-8125 4250);
DISPLAY INVISIBLE (-8125 4250);
FORCEADD OFFPAGE..4
R 2
(-7875 4400);
FORCEPROP 2 LAST $XR1 151 
J 0
(-8247 4400);
DISPLAY 0.638298 (-8247 4400);
PAINT MONO (-8247 4400);
FORCEPROP 2 LAST $XR0 150 
J 0
(-8127 4400);
DISPLAY 0.638298 (-8127 4400);
PAINT MONO (-8127 4400);
FORCEPROP 2 LAST CDS_LIB standard
J 0
(-7875 4400);
DISPLAY INVISIBLE (-7875 4400);
FORCEPROP 1 LAST OFFPAGE TRUE
J 2
(-8200 4275);
DISPLAY 0.872340 (-8200 4275);
PAINT GREEN (-8200 4275);
DISPLAY INVISIBLE (-8200 4275);
FORCEPROP 1 LAST COMMENT_BODY TRUE
J 2
(-7850 4300);
DISPLAY 0.872340 (-7850 4300);
PAINT GREEN (-7850 4300);
DISPLAY INVISIBLE (-7850 4300);
FORCEPROP 2 LAST PATH I29
J 0
(-8150 4450);
DISPLAY 0.680851 (-8150 4450);
DISPLAY INVISIBLE (-8150 4450);
FORCEADD OFFPAGE..3
R 2
(-7875 2950);
FORCEPROP 2 LAST $XR0 34 
J 0
(-8124 2950);
DISPLAY 0.638298 (-8124 2950);
PAINT MONO (-8124 2950);
FORCEPROP 2 LAST CDS_LIB standard
J 0
(-7875 2950);
DISPLAY INVISIBLE (-7875 2950);
FORCEPROP 1 LAST OFFPAGE TRUE
J 2
(-8200 2825);
DISPLAY 0.872340 (-8200 2825);
PAINT GREEN (-8200 2825);
DISPLAY INVISIBLE (-8200 2825);
FORCEPROP 1 LAST COMMENT_BODY TRUE
J 2
(-7825 2850);
DISPLAY 0.872340 (-7825 2850);
PAINT GREEN (-7825 2850);
DISPLAY INVISIBLE (-7825 2850);
FORCEPROP 2 LAST PATH I3
J 0
(-8100 3000);
DISPLAY 0.680851 (-8100 3000);
DISPLAY INVISIBLE (-8100 3000);
FORCEADD OFFPAGE..4
R 2
(-7875 4350);
FORCEPROP 2 LAST $XR1 151 
J 0
(-8247 4350);
DISPLAY 0.638298 (-8247 4350);
PAINT MONO (-8247 4350);
FORCEPROP 2 LAST $XR0 150 
J 0
(-8127 4350);
DISPLAY 0.638298 (-8127 4350);
PAINT MONO (-8127 4350);
FORCEPROP 2 LAST CDS_LIB standard
J 0
(-7875 4350);
DISPLAY INVISIBLE (-7875 4350);
FORCEPROP 1 LAST OFFPAGE TRUE
J 2
(-8200 4225);
DISPLAY 0.872340 (-8200 4225);
PAINT GREEN (-8200 4225);
DISPLAY INVISIBLE (-8200 4225);
FORCEPROP 1 LAST COMMENT_BODY TRUE
J 2
(-7850 4250);
DISPLAY 0.872340 (-7850 4250);
PAINT GREEN (-7850 4250);
DISPLAY INVISIBLE (-7850 4250);
FORCEPROP 2 LAST PATH I30
J 0
(-8125 4400);
DISPLAY 0.680851 (-8125 4400);
DISPLAY INVISIBLE (-8125 4400);
FORCEADD OFFPAGE..2
R 2
(-7875 4450);
FORCEPROP 2 LAST $XR1 150 
J 0
(-8250 4450);
DISPLAY 0.638298 (-8250 4450);
PAINT MONO (-8250 4450);
FORCEPROP 2 LAST $XR0 151 
J 0
(-8130 4450);
DISPLAY 0.638298 (-8130 4450);
PAINT MONO (-8130 4450);
FORCEPROP 2 LAST CDS_LIB standard
J 0
(-7875 4450);
DISPLAY INVISIBLE (-7875 4450);
FORCEPROP 1 LAST OFFPAGE TRUE
J 2
(-8200 4325);
DISPLAY 0.872340 (-8200 4325);
PAINT GREEN (-8200 4325);
DISPLAY INVISIBLE (-8200 4325);
FORCEPROP 1 LAST COMMENT_BODY TRUE
J 2
(-7830 4355);
DISPLAY 0.872340 (-7830 4355);
PAINT GREEN (-7830 4355);
DISPLAY INVISIBLE (-7830 4355);
FORCEPROP 2 LAST PATH I31
J 0
(-8150 4500);
DISPLAY 0.680851 (-8150 4500);
DISPLAY INVISIBLE (-8150 4500);
FORCEADD OFFPAGE..4
R 2
(-7875 4500);
FORCEPROP 2 LAST $XR0 254 
J 0
(-8127 4500);
DISPLAY 0.638298 (-8127 4500);
PAINT MONO (-8127 4500);
FORCEPROP 2 LAST CDS_LIB standard
J 0
(-7875 4500);
DISPLAY INVISIBLE (-7875 4500);
FORCEPROP 1 LAST OFFPAGE TRUE
J 2
(-8200 4375);
DISPLAY 0.872340 (-8200 4375);
PAINT GREEN (-8200 4375);
DISPLAY INVISIBLE (-8200 4375);
FORCEPROP 1 LAST COMMENT_BODY TRUE
J 2
(-7850 4400);
DISPLAY 0.872340 (-7850 4400);
PAINT GREEN (-7850 4400);
DISPLAY INVISIBLE (-7850 4400);
FORCEPROP 2 LAST PATH I32
J 0
(-7825 4575);
DISPLAY 0.680851 (-7825 4575);
DISPLAY INVISIBLE (-7825 4575);
FORCEADD OFFPAGE..2
R 2
(-7875 4550);
FORCEPROP 2 LAST $XR1 150 
J 0
(-8250 4550);
DISPLAY 0.638298 (-8250 4550);
PAINT MONO (-8250 4550);
FORCEPROP 2 LAST $XR0 151 
J 0
(-8130 4550);
DISPLAY 0.638298 (-8130 4550);
PAINT MONO (-8130 4550);
FORCEPROP 2 LAST CDS_LIB standard
J 0
(-7875 4550);
DISPLAY INVISIBLE (-7875 4550);
FORCEPROP 1 LAST OFFPAGE TRUE
J 2
(-8200 4425);
DISPLAY 0.872340 (-8200 4425);
PAINT GREEN (-8200 4425);
DISPLAY INVISIBLE (-8200 4425);
FORCEPROP 1 LAST COMMENT_BODY TRUE
J 2
(-7830 4455);
DISPLAY 0.872340 (-7830 4455);
PAINT GREEN (-7830 4455);
DISPLAY INVISIBLE (-7830 4455);
FORCEPROP 2 LAST PATH I33
J 0
(-8150 4600);
DISPLAY 0.680851 (-8150 4600);
DISPLAY INVISIBLE (-8150 4600);
FORCEADD OFFPAGE..2
R 2
(-7875 4650);
FORCEPROP 2 LAST $XR1 159 
J 0
(-8219 4650);
DISPLAY 0.638298 (-8219 4650);
PAINT MONO (-8219 4650);
FORCEPROP 2 LAST $XR0 83 
J 0
(-8099 4650);
DISPLAY 0.638298 (-8099 4650);
PAINT MONO (-8099 4650);
FORCEPROP 2 LAST CDS_LIB standard
J 0
(-7875 4650);
DISPLAY INVISIBLE (-7875 4650);
FORCEPROP 1 LAST OFFPAGE TRUE
J 2
(-8200 4525);
DISPLAY 0.872340 (-8200 4525);
PAINT GREEN (-8200 4525);
DISPLAY INVISIBLE (-8200 4525);
FORCEPROP 1 LAST COMMENT_BODY TRUE
J 2
(-7830 4555);
DISPLAY 0.872340 (-7830 4555);
PAINT GREEN (-7830 4555);
DISPLAY INVISIBLE (-7830 4555);
FORCEPROP 2 LAST PATH I34
J 0
(-8125 4700);
DISPLAY 0.680851 (-8125 4700);
DISPLAY INVISIBLE (-8125 4700);
FORCEADD OFFPAGE..2
R 2
(-7875 4600);
FORCEPROP 2 LAST $XR0 171 
J 0
(-8130 4600);
DISPLAY 0.638298 (-8130 4600);
PAINT MONO (-8130 4600);
FORCEPROP 2 LAST CDS_LIB standard
J 0
(-7875 4600);
DISPLAY INVISIBLE (-7875 4600);
FORCEPROP 1 LAST OFFPAGE TRUE
J 2
(-8200 4475);
DISPLAY 0.872340 (-8200 4475);
PAINT GREEN (-8200 4475);
DISPLAY INVISIBLE (-8200 4475);
FORCEPROP 1 LAST COMMENT_BODY TRUE
J 2
(-7830 4505);
DISPLAY 0.872340 (-7830 4505);
PAINT GREEN (-7830 4505);
DISPLAY INVISIBLE (-7830 4505);
FORCEPROP 2 LAST PATH I35
J 0
(-8150 4650);
DISPLAY 0.680851 (-8150 4650);
DISPLAY INVISIBLE (-8150 4650);
FORCEADD OFFPAGE..2
R 2
(-7875 4700);
FORCEPROP 2 LAST $XR0 159 
J 0
(-8130 4700);
DISPLAY 0.638298 (-8130 4700);
PAINT MONO (-8130 4700);
FORCEPROP 2 LAST CDS_LIB standard
J 0
(-7875 4700);
DISPLAY INVISIBLE (-7875 4700);
FORCEPROP 1 LAST OFFPAGE TRUE
J 2
(-8200 4575);
DISPLAY 0.872340 (-8200 4575);
PAINT GREEN (-8200 4575);
DISPLAY INVISIBLE (-8200 4575);
FORCEPROP 1 LAST COMMENT_BODY TRUE
J 2
(-7830 4605);
DISPLAY 0.872340 (-7830 4605);
PAINT GREEN (-7830 4605);
DISPLAY INVISIBLE (-7830 4605);
FORCEPROP 2 LAST PATH I36
J 0
(-8150 4750);
DISPLAY 0.680851 (-8150 4750);
DISPLAY INVISIBLE (-8150 4750);
FORCEADD OFFPAGE..2
R 2
(-7875 4800);
FORCEPROP 2 LAST $XR1 159 
J 0
(-8219 4800);
DISPLAY 0.638298 (-8219 4800);
PAINT MONO (-8219 4800);
FORCEPROP 2 LAST $XR0 83 
J 0
(-8099 4800);
DISPLAY 0.638298 (-8099 4800);
PAINT MONO (-8099 4800);
FORCEPROP 2 LAST CDS_LIB standard
J 0
(-7875 4800);
DISPLAY INVISIBLE (-7875 4800);
FORCEPROP 1 LAST OFFPAGE TRUE
J 2
(-8200 4675);
DISPLAY 0.872340 (-8200 4675);
PAINT GREEN (-8200 4675);
DISPLAY INVISIBLE (-8200 4675);
FORCEPROP 1 LAST COMMENT_BODY TRUE
J 2
(-7830 4705);
DISPLAY 0.872340 (-7830 4705);
PAINT GREEN (-7830 4705);
DISPLAY INVISIBLE (-7830 4705);
FORCEPROP 2 LAST PATH I37
J 0
(-8125 4850);
DISPLAY 0.680851 (-8125 4850);
DISPLAY INVISIBLE (-8125 4850);
FORCEADD OFFPAGE..2
R 2
(-7875 4750);
FORCEPROP 2 LAST $XR0 171 
J 0
(-8130 4750);
DISPLAY 0.638298 (-8130 4750);
PAINT MONO (-8130 4750);
FORCEPROP 2 LAST CDS_LIB standard
J 0
(-7875 4750);
DISPLAY INVISIBLE (-7875 4750);
FORCEPROP 1 LAST OFFPAGE TRUE
J 2
(-8200 4625);
DISPLAY 0.872340 (-8200 4625);
PAINT GREEN (-8200 4625);
DISPLAY INVISIBLE (-8200 4625);
FORCEPROP 1 LAST COMMENT_BODY TRUE
J 2
(-7830 4655);
DISPLAY 0.872340 (-7830 4655);
PAINT GREEN (-7830 4655);
DISPLAY INVISIBLE (-7830 4655);
FORCEPROP 2 LAST PATH I38
J 0
(-8150 4800);
DISPLAY 0.680851 (-8150 4800);
DISPLAY INVISIBLE (-8150 4800);
FORCEADD OFFPAGE..2
R 2
(-7875 4900);
FORCEPROP 2 LAST $XR1 159 
J 0
(-8219 4900);
DISPLAY 0.638298 (-8219 4900);
PAINT MONO (-8219 4900);
FORCEPROP 2 LAST $XR0 83 
J 0
(-8099 4900);
DISPLAY 0.638298 (-8099 4900);
PAINT MONO (-8099 4900);
FORCEPROP 2 LAST CDS_LIB standard
J 0
(-7875 4900);
DISPLAY INVISIBLE (-7875 4900);
FORCEPROP 1 LAST OFFPAGE TRUE
J 2
(-8200 4775);
DISPLAY 0.872340 (-8200 4775);
PAINT GREEN (-8200 4775);
DISPLAY INVISIBLE (-8200 4775);
FORCEPROP 1 LAST COMMENT_BODY TRUE
J 2
(-7830 4805);
DISPLAY 0.872340 (-7830 4805);
PAINT GREEN (-7830 4805);
DISPLAY INVISIBLE (-7830 4805);
FORCEPROP 2 LAST PATH I39
J 0
(-8125 4950);
DISPLAY 0.680851 (-8125 4950);
DISPLAY INVISIBLE (-8125 4950);
FORCEADD OFFPAGE..4
R 2
(-7875 3000);
FORCEPROP 2 LAST $XR0 34 
J 0
(-8096 3000);
DISPLAY 0.638298 (-8096 3000);
PAINT MONO (-8096 3000);
FORCEPROP 2 LAST CDS_LIB standard
J 0
(-7875 3000);
DISPLAY INVISIBLE (-7875 3000);
FORCEPROP 1 LAST OFFPAGE TRUE
J 2
(-8200 2875);
DISPLAY 0.872340 (-8200 2875);
PAINT GREEN (-8200 2875);
DISPLAY INVISIBLE (-8200 2875);
FORCEPROP 1 LAST COMMENT_BODY TRUE
J 2
(-7850 2900);
DISPLAY 0.872340 (-7850 2900);
PAINT GREEN (-7850 2900);
DISPLAY INVISIBLE (-7850 2900);
FORCEPROP 2 LAST PATH I4
J 0
(-8075 3050);
DISPLAY 0.680851 (-8075 3050);
DISPLAY INVISIBLE (-8075 3050);
FORCEADD OFFPAGE..2
R 2
(-7875 4850);
FORCEPROP 2 LAST $XR0 159 
J 0
(-8130 4850);
DISPLAY 0.638298 (-8130 4850);
PAINT MONO (-8130 4850);
FORCEPROP 2 LAST CDS_LIB standard
J 0
(-7875 4850);
DISPLAY INVISIBLE (-7875 4850);
FORCEPROP 1 LAST OFFPAGE TRUE
J 2
(-8200 4725);
DISPLAY 0.872340 (-8200 4725);
PAINT GREEN (-8200 4725);
DISPLAY INVISIBLE (-8200 4725);
FORCEPROP 1 LAST COMMENT_BODY TRUE
J 2
(-7830 4755);
DISPLAY 0.872340 (-7830 4755);
PAINT GREEN (-7830 4755);
DISPLAY INVISIBLE (-7830 4755);
FORCEPROP 2 LAST PATH I40
J 0
(-8150 4900);
DISPLAY 0.680851 (-8150 4900);
DISPLAY INVISIBLE (-8150 4900);
FORCEADD OFFPAGE..2
R 2
(-7875 4950);
FORCEPROP 2 LAST $XR0 159 
J 0
(-8130 4950);
DISPLAY 0.638298 (-8130 4950);
PAINT MONO (-8130 4950);
FORCEPROP 2 LAST CDS_LIB standard
J 0
(-7875 4950);
DISPLAY INVISIBLE (-7875 4950);
FORCEPROP 1 LAST OFFPAGE TRUE
J 2
(-8200 4825);
DISPLAY 0.872340 (-8200 4825);
PAINT GREEN (-8200 4825);
DISPLAY INVISIBLE (-8200 4825);
FORCEPROP 1 LAST COMMENT_BODY TRUE
J 2
(-7830 4855);
DISPLAY 0.872340 (-7830 4855);
PAINT GREEN (-7830 4855);
DISPLAY INVISIBLE (-7830 4855);
FORCEPROP 2 LAST PATH I41
J 0
(-8150 5000);
DISPLAY 0.680851 (-8150 5000);
DISPLAY INVISIBLE (-8150 5000);
FORCEADD OFFPAGE..2
R 2
(-7875 5000);
FORCEPROP 2 LAST $XR1 159 
J 0
(-8219 5000);
DISPLAY 0.638298 (-8219 5000);
PAINT MONO (-8219 5000);
FORCEPROP 2 LAST $XR0 83 
J 0
(-8099 5000);
DISPLAY 0.638298 (-8099 5000);
PAINT MONO (-8099 5000);
FORCEPROP 2 LAST CDS_LIB standard
J 0
(-7875 5000);
DISPLAY INVISIBLE (-7875 5000);
FORCEPROP 1 LAST OFFPAGE TRUE
J 2
(-8200 4875);
DISPLAY 0.872340 (-8200 4875);
PAINT GREEN (-8200 4875);
DISPLAY INVISIBLE (-8200 4875);
FORCEPROP 1 LAST COMMENT_BODY TRUE
J 2
(-7830 4905);
DISPLAY 0.872340 (-7830 4905);
PAINT GREEN (-7830 4905);
DISPLAY INVISIBLE (-7830 4905);
FORCEPROP 2 LAST PATH I42
J 0
(-8125 5050);
DISPLAY 0.680851 (-8125 5050);
DISPLAY INVISIBLE (-8125 5050);
FORCEADD Q_RES..1
R 2
(-6850 4300);
FORCEPROP 1 LAST LOCATION R172
J 0
(-7075 4300);
DISPLAY 0.489362 (-7075 4300);
PAINT SKYBLUE (-7075 4300);
FORCEPROP 0 LAST $SEC 1
J 0
(-6950 4350);
DISPLAY 0.680851 (-6950 4350);
PAINT MONO (-6950 4350);
DISPLAY INVISIBLE (-6950 4350);
FORCEPROP 0 LAST CDS_SEC 1
J 0
(-6950 4350);
DISPLAY 1.021277 (-6950 4350);
DISPLAY INVISIBLE (-6950 4350);
FORCEPROP 1 LASTPIN (-6750 4300) $PN 1
J 2
(-6762 4312);
DISPLAY 0.489362 (-6762 4312);
PAINT MONO (-6762 4312);
FORCEPROP 1 LASTPIN (-6950 4300) $PN 2
J 2
(-6912 4312);
DISPLAY 0.489362 (-6912 4312);
PAINT MONO (-6912 4312);
FORCEPROP 1 LAST VALUE 33
J 0
(-6725 4300);
DISPLAY 0.489362 (-6725 4300);
PAINT SKYBLUE (-6725 4300);
FORCEPROP 2 LAST CDS_LIB pure_quanta
J 0
(-6850 4300);
DISPLAY INVISIBLE (-6850 4300);
FORCEPROP 2 LAST BOM_COST MEM
J 0
(-6875 4450);
DISPLAY 0.744681 (-6875 4450);
PAINT WHITE (-6875 4450);
DISPLAY INVISIBLE (-6875 4450);
FORCEPROP 1 LAST WATTAGE 1/16W
J 0
(-6775 4225);
DISPLAY 0.489362 (-6775 4225);
PAINT SKYBLUE (-6775 4225);
DISPLAY INVISIBLE (-6775 4225);
FORCEPROP 1 LAST MATERIAL CHIP
J 0
(-7025 4275);
DISPLAY 0.489362 (-7025 4275);
PAINT SKYBLUE (-7025 4275);
DISPLAY INVISIBLE (-7025 4275);
FORCEPROP 1 LAST TOLERANCE 5%
J 2
(-6725 4275);
DISPLAY 0.489362 (-6725 4275);
PAINT SKYBLUE (-6725 4275);
DISPLAY INVISIBLE (-6725 4275);
FORCEPROP 1 LAST PACK_TYPE 0402LF
J 0
(-7025 4225);
DISPLAY 0.489362 (-7025 4225);
PAINT SKYBLUE (-7025 4225);
DISPLAY INVISIBLE (-7025 4225);
FORCEPROP 1 LAST PATH I43
J 2
(-6800 4450);
DISPLAY 0.978723 (-6800 4450);
PAINT WHITE (-6800 4450);
DISPLAY INVISIBLE (-6800 4450);
FORCEPROP 1 LAST PART_NUMBER CS03302JB10
J 0
(-6950 4350);
DISPLAY 0.489362 (-6950 4350);
PAINT SKYBLUE (-6950 4350);
DISPLAY INVISIBLE (-6950 4350);
FORCEADD Q_RES..1
R 2
(-6850 4450);
FORCEPROP 1 LAST LOCATION R58
J 0
(-7075 4450);
DISPLAY 0.489362 (-7075 4450);
PAINT SKYBLUE (-7075 4450);
FORCEPROP 0 LAST $SEC 1
J 0
(-6725 4475);
DISPLAY 0.680851 (-6725 4475);
PAINT MONO (-6725 4475);
DISPLAY INVISIBLE (-6725 4475);
FORCEPROP 0 LAST CDS_SEC 1
J 0
(-6725 4475);
DISPLAY 0.680851 (-6725 4475);
DISPLAY INVISIBLE (-6725 4475);
FORCEPROP 1 LASTPIN (-6750 4450) $PN 1
J 2
(-6762 4462);
DISPLAY 0.489362 (-6762 4462);
PAINT MONO (-6762 4462);
FORCEPROP 1 LASTPIN (-6950 4450) $PN 2
J 2
(-6912 4462);
DISPLAY 0.489362 (-6912 4462);
PAINT MONO (-6912 4462);
FORCEPROP 1 LAST VALUE 33
J 0
(-6725 4450);
DISPLAY 0.489362 (-6725 4450);
PAINT SKYBLUE (-6725 4450);
FORCEPROP 1 LAST PACK_TYPE 0402LF
J 0
(-7025 4375);
DISPLAY 0.489362 (-7025 4375);
PAINT SKYBLUE (-7025 4375);
DISPLAY INVISIBLE (-7025 4375);
FORCEPROP 1 LAST TOLERANCE 5%
J 2
(-6725 4425);
DISPLAY 0.489362 (-6725 4425);
PAINT SKYBLUE (-6725 4425);
DISPLAY INVISIBLE (-6725 4425);
FORCEPROP 1 LAST MATERIAL CHIP
J 0
(-7025 4425);
DISPLAY 0.489362 (-7025 4425);
PAINT SKYBLUE (-7025 4425);
DISPLAY INVISIBLE (-7025 4425);
FORCEPROP 1 LAST WATTAGE 1/16W
J 0
(-6775 4375);
DISPLAY 0.489362 (-6775 4375);
PAINT SKYBLUE (-6775 4375);
DISPLAY INVISIBLE (-6775 4375);
FORCEPROP 2 LAST CDS_LIB pure_quanta
J 0
(-6850 4450);
DISPLAY INVISIBLE (-6850 4450);
FORCEPROP 2 LAST BOM_COST MEM
J 0
(-6875 4600);
DISPLAY 0.744681 (-6875 4600);
PAINT WHITE (-6875 4600);
DISPLAY INVISIBLE (-6875 4600);
FORCEPROP 1 LAST PATH I44
J 2
(-6800 4600);
DISPLAY 0.978723 (-6800 4600);
PAINT WHITE (-6800 4600);
DISPLAY INVISIBLE (-6800 4600);
FORCEPROP 1 LAST PART_NUMBER CS03302JB10
J 0
(-6950 4500);
DISPLAY 0.489362 (-6950 4500);
PAINT SKYBLUE (-6950 4500);
DISPLAY INVISIBLE (-6950 4500);
FORCEADD Q_RES..1
R 2
(-6850 4550);
FORCEPROP 1 LAST LOCATION R167
J 0
(-7075 4550);
DISPLAY 0.489362 (-7075 4550);
PAINT SKYBLUE (-7075 4550);
FORCEPROP 0 LAST $SEC 1
J 0
(-6950 4600);
DISPLAY 0.680851 (-6950 4600);
PAINT MONO (-6950 4600);
DISPLAY INVISIBLE (-6950 4600);
FORCEPROP 0 LAST CDS_SEC 1
J 0
(-6950 4600);
DISPLAY 1.021277 (-6950 4600);
DISPLAY INVISIBLE (-6950 4600);
FORCEPROP 1 LASTPIN (-6750 4550) $PN 1
J 2
(-6762 4562);
DISPLAY 0.489362 (-6762 4562);
PAINT MONO (-6762 4562);
FORCEPROP 1 LASTPIN (-6950 4550) $PN 2
J 2
(-6912 4562);
DISPLAY 0.489362 (-6912 4562);
PAINT MONO (-6912 4562);
FORCEPROP 1 LAST VALUE 0
J 0
(-6725 4550);
DISPLAY 0.489362 (-6725 4550);
PAINT SKYBLUE (-6725 4550);
FORCEPROP 2 LAST BOM_COST MEM
J 0
(-6875 4700);
DISPLAY 0.744681 (-6875 4700);
PAINT WHITE (-6875 4700);
DISPLAY INVISIBLE (-6875 4700);
FORCEPROP 2 LAST CDS_LIB pure_quanta
J 0
(-6850 4550);
DISPLAY INVISIBLE (-6850 4550);
FORCEPROP 1 LAST WATTAGE 1/16W
J 0
(-6775 4475);
DISPLAY 0.489362 (-6775 4475);
PAINT SKYBLUE (-6775 4475);
DISPLAY INVISIBLE (-6775 4475);
FORCEPROP 1 LAST MATERIAL CHIP
J 0
(-7025 4525);
DISPLAY 0.489362 (-7025 4525);
PAINT SKYBLUE (-7025 4525);
DISPLAY INVISIBLE (-7025 4525);
FORCEPROP 1 LAST TOLERANCE 5%
J 2
(-6725 4525);
DISPLAY 0.489362 (-6725 4525);
PAINT SKYBLUE (-6725 4525);
DISPLAY INVISIBLE (-6725 4525);
FORCEPROP 1 LAST PACK_TYPE 0402LF
J 0
(-7025 4475);
DISPLAY 0.489362 (-7025 4475);
PAINT SKYBLUE (-7025 4475);
DISPLAY INVISIBLE (-7025 4475);
FORCEPROP 1 LAST PATH I45
J 2
(-6800 4700);
DISPLAY 0.978723 (-6800 4700);
PAINT WHITE (-6800 4700);
DISPLAY INVISIBLE (-6800 4700);
FORCEPROP 1 LAST PART_NUMBER CS00002JB13
J 0
(-6950 4600);
DISPLAY 0.489362 (-6950 4600);
PAINT SKYBLUE (-6950 4600);
DISPLAY INVISIBLE (-6950 4600);
FORCEADD Q_RES..1
R 2
(-6850 4600);
FORCEPROP 1 LAST LOCATION R49
J 0
(-7075 4600);
DISPLAY 0.489362 (-7075 4600);
PAINT SKYBLUE (-7075 4600);
FORCEPROP 0 LAST $SEC 1
J 0
(-6900 4650);
DISPLAY 0.680851 (-6900 4650);
PAINT MONO (-6900 4650);
DISPLAY INVISIBLE (-6900 4650);
FORCEPROP 0 LAST CDS_SEC 1
J 0
(-6900 4650);
DISPLAY 1.021277 (-6900 4650);
DISPLAY INVISIBLE (-6900 4650);
FORCEPROP 1 LASTPIN (-6750 4600) $PN 1
J 2
(-6762 4612);
DISPLAY 0.489362 (-6762 4612);
PAINT MONO (-6762 4612);
FORCEPROP 1 LASTPIN (-6950 4600) $PN 2
J 2
(-6912 4612);
DISPLAY 0.489362 (-6912 4612);
PAINT MONO (-6912 4612);
FORCEPROP 1 LAST VALUE 33
J 0
(-6725 4600);
DISPLAY 0.489362 (-6725 4600);
PAINT SKYBLUE (-6725 4600);
FORCEPROP 2 LAST CDS_LIB pure_quanta
J 0
(-6850 4600);
DISPLAY INVISIBLE (-6850 4600);
FORCEPROP 2 LAST BOM_COST MEM
J 0
(-6875 4750);
DISPLAY 0.744681 (-6875 4750);
PAINT WHITE (-6875 4750);
DISPLAY INVISIBLE (-6875 4750);
FORCEPROP 1 LAST WATTAGE 1/16W
J 0
(-6775 4525);
DISPLAY 0.489362 (-6775 4525);
PAINT SKYBLUE (-6775 4525);
DISPLAY INVISIBLE (-6775 4525);
FORCEPROP 1 LAST MATERIAL CHIP
J 0
(-7025 4575);
DISPLAY 0.489362 (-7025 4575);
PAINT SKYBLUE (-7025 4575);
DISPLAY INVISIBLE (-7025 4575);
FORCEPROP 1 LAST TOLERANCE 5%
J 2
(-6725 4575);
DISPLAY 0.489362 (-6725 4575);
PAINT SKYBLUE (-6725 4575);
DISPLAY INVISIBLE (-6725 4575);
FORCEPROP 1 LAST PACK_TYPE 0402LF
J 0
(-7025 4525);
DISPLAY 0.489362 (-7025 4525);
PAINT SKYBLUE (-7025 4525);
DISPLAY INVISIBLE (-7025 4525);
FORCEPROP 1 LAST PATH I46
J 2
(-6800 4750);
DISPLAY 0.978723 (-6800 4750);
PAINT WHITE (-6800 4750);
DISPLAY INVISIBLE (-6800 4750);
FORCEPROP 1 LAST PART_NUMBER CS03302JB10
J 0
(-6950 4650);
DISPLAY 0.489362 (-6950 4650);
PAINT SKYBLUE (-6950 4650);
DISPLAY INVISIBLE (-6950 4650);
FORCEADD Q_RES..1
R 2
(-6850 4650);
FORCEPROP 1 LAST LOCATION R165
J 0
(-7075 4650);
DISPLAY 0.489362 (-7075 4650);
PAINT SKYBLUE (-7075 4650);
FORCEPROP 0 LAST $SEC 1
J 0
(-6975 4700);
DISPLAY 0.680851 (-6975 4700);
PAINT MONO (-6975 4700);
DISPLAY INVISIBLE (-6975 4700);
FORCEPROP 0 LAST CDS_SEC 1
J 0
(-6975 4700);
DISPLAY 1.021277 (-6975 4700);
DISPLAY INVISIBLE (-6975 4700);
FORCEPROP 1 LASTPIN (-6750 4650) $PN 1
J 2
(-6762 4662);
DISPLAY 0.489362 (-6762 4662);
PAINT MONO (-6762 4662);
FORCEPROP 1 LASTPIN (-6950 4650) $PN 2
J 2
(-6912 4662);
DISPLAY 0.489362 (-6912 4662);
PAINT MONO (-6912 4662);
FORCEPROP 1 LAST VALUE 33
J 0
(-6725 4650);
DISPLAY 0.489362 (-6725 4650);
PAINT SKYBLUE (-6725 4650);
FORCEPROP 1 LAST PACK_TYPE 0402LF
J 0
(-7025 4575);
DISPLAY 0.489362 (-7025 4575);
PAINT SKYBLUE (-7025 4575);
DISPLAY INVISIBLE (-7025 4575);
FORCEPROP 1 LAST TOLERANCE 5%
J 2
(-6725 4625);
DISPLAY 0.489362 (-6725 4625);
PAINT SKYBLUE (-6725 4625);
DISPLAY INVISIBLE (-6725 4625);
FORCEPROP 1 LAST MATERIAL CHIP
J 0
(-7025 4625);
DISPLAY 0.489362 (-7025 4625);
PAINT SKYBLUE (-7025 4625);
DISPLAY INVISIBLE (-7025 4625);
FORCEPROP 1 LAST WATTAGE 1/16W
J 0
(-6775 4575);
DISPLAY 0.489362 (-6775 4575);
PAINT SKYBLUE (-6775 4575);
DISPLAY INVISIBLE (-6775 4575);
FORCEPROP 2 LAST CDS_LIB pure_quanta
J 0
(-6850 4650);
DISPLAY INVISIBLE (-6850 4650);
FORCEPROP 2 LAST BOM_COST MEM
J 0
(-6875 4800);
DISPLAY 0.744681 (-6875 4800);
PAINT WHITE (-6875 4800);
DISPLAY INVISIBLE (-6875 4800);
FORCEPROP 1 LAST PATH I47
J 2
(-6800 4800);
DISPLAY 0.978723 (-6800 4800);
PAINT WHITE (-6800 4800);
DISPLAY INVISIBLE (-6800 4800);
FORCEPROP 1 LAST PART_NUMBER CS03302JB10
J 0
(-6950 4700);
DISPLAY 0.489362 (-6950 4700);
PAINT SKYBLUE (-6950 4700);
DISPLAY INVISIBLE (-6950 4700);
FORCEADD Q_RES..1
R 2
(-6850 4800);
FORCEPROP 1 LAST LOCATION R169
J 0
(-7075 4800);
DISPLAY 0.489362 (-7075 4800);
PAINT SKYBLUE (-7075 4800);
FORCEPROP 0 LAST $SEC 1
J 0
(-6950 4850);
DISPLAY 0.680851 (-6950 4850);
PAINT MONO (-6950 4850);
DISPLAY INVISIBLE (-6950 4850);
FORCEPROP 0 LAST CDS_SEC 1
J 0
(-6950 4850);
DISPLAY 1.021277 (-6950 4850);
DISPLAY INVISIBLE (-6950 4850);
FORCEPROP 1 LASTPIN (-6750 4800) $PN 1
J 2
(-6762 4812);
DISPLAY 0.489362 (-6762 4812);
PAINT MONO (-6762 4812);
FORCEPROP 1 LASTPIN (-6950 4800) $PN 2
J 2
(-6912 4812);
DISPLAY 0.489362 (-6912 4812);
PAINT MONO (-6912 4812);
FORCEPROP 1 LAST VALUE 33
J 0
(-6725 4800);
DISPLAY 0.489362 (-6725 4800);
PAINT SKYBLUE (-6725 4800);
FORCEPROP 1 LAST PACK_TYPE 0402LF
J 0
(-7025 4725);
DISPLAY 0.489362 (-7025 4725);
PAINT SKYBLUE (-7025 4725);
DISPLAY INVISIBLE (-7025 4725);
FORCEPROP 1 LAST TOLERANCE 5%
J 2
(-6725 4775);
DISPLAY 0.489362 (-6725 4775);
PAINT SKYBLUE (-6725 4775);
DISPLAY INVISIBLE (-6725 4775);
FORCEPROP 1 LAST MATERIAL CHIP
J 0
(-7025 4775);
DISPLAY 0.489362 (-7025 4775);
PAINT SKYBLUE (-7025 4775);
DISPLAY INVISIBLE (-7025 4775);
FORCEPROP 1 LAST WATTAGE 1/16W
J 0
(-6775 4725);
DISPLAY 0.489362 (-6775 4725);
PAINT SKYBLUE (-6775 4725);
DISPLAY INVISIBLE (-6775 4725);
FORCEPROP 2 LAST BOM_COST MEM
J 0
(-6875 4950);
DISPLAY 0.744681 (-6875 4950);
PAINT WHITE (-6875 4950);
DISPLAY INVISIBLE (-6875 4950);
FORCEPROP 2 LAST CDS_LIB pure_quanta
J 0
(-6850 4800);
DISPLAY INVISIBLE (-6850 4800);
FORCEPROP 1 LAST PATH I48
J 2
(-6800 4950);
DISPLAY 0.978723 (-6800 4950);
PAINT WHITE (-6800 4950);
DISPLAY INVISIBLE (-6800 4950);
FORCEPROP 1 LAST PART_NUMBER CS03302JB10
J 0
(-6950 4850);
DISPLAY 0.489362 (-6950 4850);
PAINT SKYBLUE (-6950 4850);
DISPLAY INVISIBLE (-6950 4850);
FORCEADD Q_RES..1
R 2
(-6850 4750);
FORCEPROP 1 LAST LOCATION R50
J 0
(-7075 4750);
DISPLAY 0.489362 (-7075 4750);
PAINT SKYBLUE (-7075 4750);
FORCEPROP 0 LAST $SEC 1
J 0
(-6900 4800);
DISPLAY 0.680851 (-6900 4800);
PAINT MONO (-6900 4800);
DISPLAY INVISIBLE (-6900 4800);
FORCEPROP 0 LAST CDS_SEC 1
J 0
(-6900 4800);
DISPLAY 1.021277 (-6900 4800);
DISPLAY INVISIBLE (-6900 4800);
FORCEPROP 1 LASTPIN (-6750 4750) $PN 1
J 2
(-6762 4762);
DISPLAY 0.489362 (-6762 4762);
PAINT MONO (-6762 4762);
FORCEPROP 1 LASTPIN (-6950 4750) $PN 2
J 2
(-6912 4762);
DISPLAY 0.489362 (-6912 4762);
PAINT MONO (-6912 4762);
FORCEPROP 1 LAST VALUE 33
J 0
(-6725 4750);
DISPLAY 0.489362 (-6725 4750);
PAINT SKYBLUE (-6725 4750);
FORCEPROP 1 LAST PACK_TYPE 0402LF
J 0
(-7025 4675);
DISPLAY 0.489362 (-7025 4675);
PAINT SKYBLUE (-7025 4675);
DISPLAY INVISIBLE (-7025 4675);
FORCEPROP 1 LAST TOLERANCE 5%
J 2
(-6725 4725);
DISPLAY 0.489362 (-6725 4725);
PAINT SKYBLUE (-6725 4725);
DISPLAY INVISIBLE (-6725 4725);
FORCEPROP 1 LAST MATERIAL CHIP
J 0
(-7025 4725);
DISPLAY 0.489362 (-7025 4725);
PAINT SKYBLUE (-7025 4725);
DISPLAY INVISIBLE (-7025 4725);
FORCEPROP 1 LAST WATTAGE 1/16W
J 0
(-6775 4675);
DISPLAY 0.489362 (-6775 4675);
PAINT SKYBLUE (-6775 4675);
DISPLAY INVISIBLE (-6775 4675);
FORCEPROP 2 LAST CDS_LIB pure_quanta
J 0
(-6850 4750);
DISPLAY INVISIBLE (-6850 4750);
FORCEPROP 2 LAST BOM_COST MEM
J 0
(-6875 4900);
DISPLAY 0.744681 (-6875 4900);
PAINT WHITE (-6875 4900);
DISPLAY INVISIBLE (-6875 4900);
FORCEPROP 1 LAST PATH I49
J 2
(-6800 4900);
DISPLAY 0.978723 (-6800 4900);
PAINT WHITE (-6800 4900);
DISPLAY INVISIBLE (-6800 4900);
FORCEPROP 1 LAST PART_NUMBER CS03302JB10
J 0
(-6950 4800);
DISPLAY 0.489362 (-6950 4800);
PAINT SKYBLUE (-6950 4800);
DISPLAY INVISIBLE (-6950 4800);
FORCEADD OFFPAGE..4
R 2
(-7875 3050);
FORCEPROP 2 LAST $XR1 268 
J 0
(-8247 3050);
DISPLAY 0.638298 (-8247 3050);
PAINT MONO (-8247 3050);
FORCEPROP 2 LAST $XR0 263 
J 0
(-8127 3050);
DISPLAY 0.638298 (-8127 3050);
PAINT MONO (-8127 3050);
FORCEPROP 2 LAST CDS_LIB standard
J 0
(-7875 3050);
DISPLAY INVISIBLE (-7875 3050);
FORCEPROP 1 LAST OFFPAGE TRUE
J 2
(-8200 2925);
DISPLAY 0.872340 (-8200 2925);
PAINT GREEN (-8200 2925);
DISPLAY INVISIBLE (-8200 2925);
FORCEPROP 1 LAST COMMENT_BODY TRUE
J 2
(-7850 2950);
DISPLAY 0.872340 (-7850 2950);
PAINT GREEN (-7850 2950);
DISPLAY INVISIBLE (-7850 2950);
FORCEPROP 2 LAST PATH I5
J 0
(-8125 3100);
DISPLAY 0.680851 (-8125 3100);
DISPLAY INVISIBLE (-8125 3100);
FORCEADD Q_RES..1
R 2
(-6850 4700);
FORCEPROP 1 LAST LOCATION R164
J 0
(-7075 4700);
DISPLAY 0.489362 (-7075 4700);
PAINT SKYBLUE (-7075 4700);
FORCEPROP 0 LAST $SEC 1
J 0
(-6975 4750);
DISPLAY 0.680851 (-6975 4750);
PAINT MONO (-6975 4750);
DISPLAY INVISIBLE (-6975 4750);
FORCEPROP 0 LAST CDS_SEC 1
J 0
(-6975 4750);
DISPLAY 1.021277 (-6975 4750);
DISPLAY INVISIBLE (-6975 4750);
FORCEPROP 1 LASTPIN (-6750 4700) $PN 1
J 2
(-6762 4712);
DISPLAY 0.489362 (-6762 4712);
PAINT MONO (-6762 4712);
FORCEPROP 1 LASTPIN (-6950 4700) $PN 2
J 2
(-6912 4712);
DISPLAY 0.489362 (-6912 4712);
PAINT MONO (-6912 4712);
FORCEPROP 1 LAST VALUE 33
J 0
(-6725 4700);
DISPLAY 0.489362 (-6725 4700);
PAINT SKYBLUE (-6725 4700);
FORCEPROP 1 LAST PACK_TYPE 0402LF
J 0
(-7025 4625);
DISPLAY 0.489362 (-7025 4625);
PAINT SKYBLUE (-7025 4625);
DISPLAY INVISIBLE (-7025 4625);
FORCEPROP 1 LAST TOLERANCE 5%
J 2
(-6725 4675);
DISPLAY 0.489362 (-6725 4675);
PAINT SKYBLUE (-6725 4675);
DISPLAY INVISIBLE (-6725 4675);
FORCEPROP 1 LAST MATERIAL CHIP
J 0
(-7025 4675);
DISPLAY 0.489362 (-7025 4675);
PAINT SKYBLUE (-7025 4675);
DISPLAY INVISIBLE (-7025 4675);
FORCEPROP 1 LAST WATTAGE 1/16W
J 0
(-6775 4625);
DISPLAY 0.489362 (-6775 4625);
PAINT SKYBLUE (-6775 4625);
DISPLAY INVISIBLE (-6775 4625);
FORCEPROP 2 LAST BOM_COST MEM
J 0
(-6875 4850);
DISPLAY 0.744681 (-6875 4850);
PAINT WHITE (-6875 4850);
DISPLAY INVISIBLE (-6875 4850);
FORCEPROP 2 LAST CDS_LIB pure_quanta
J 0
(-6850 4700);
DISPLAY INVISIBLE (-6850 4700);
FORCEPROP 1 LAST PATH I50
J 2
(-6800 4850);
DISPLAY 0.978723 (-6800 4850);
PAINT WHITE (-6800 4850);
DISPLAY INVISIBLE (-6800 4850);
FORCEPROP 1 LAST PART_NUMBER CS03302JB10
J 0
(-6950 4750);
DISPLAY 0.489362 (-6950 4750);
PAINT SKYBLUE (-6950 4750);
DISPLAY INVISIBLE (-6950 4750);
FORCEADD Q_RES..1
R 2
(-6850 4850);
FORCEPROP 1 LAST LOCATION R166
J 0
(-7075 4850);
DISPLAY 0.489362 (-7075 4850);
PAINT SKYBLUE (-7075 4850);
FORCEPROP 0 LAST $SEC 1
J 0
(-6975 4900);
DISPLAY 0.680851 (-6975 4900);
PAINT MONO (-6975 4900);
DISPLAY INVISIBLE (-6975 4900);
FORCEPROP 0 LAST CDS_SEC 1
J 0
(-6975 4900);
DISPLAY 1.021277 (-6975 4900);
DISPLAY INVISIBLE (-6975 4900);
FORCEPROP 1 LASTPIN (-6750 4850) $PN 1
J 2
(-6762 4862);
DISPLAY 0.489362 (-6762 4862);
PAINT MONO (-6762 4862);
FORCEPROP 1 LASTPIN (-6950 4850) $PN 2
J 2
(-6912 4862);
DISPLAY 0.489362 (-6912 4862);
PAINT MONO (-6912 4862);
FORCEPROP 1 LAST VALUE 33
J 0
(-6725 4850);
DISPLAY 0.489362 (-6725 4850);
PAINT SKYBLUE (-6725 4850);
FORCEPROP 1 LAST PACK_TYPE 0402LF
J 0
(-7025 4775);
DISPLAY 0.489362 (-7025 4775);
PAINT SKYBLUE (-7025 4775);
DISPLAY INVISIBLE (-7025 4775);
FORCEPROP 1 LAST TOLERANCE 5%
J 2
(-6725 4825);
DISPLAY 0.489362 (-6725 4825);
PAINT SKYBLUE (-6725 4825);
DISPLAY INVISIBLE (-6725 4825);
FORCEPROP 1 LAST MATERIAL CHIP
J 0
(-7025 4825);
DISPLAY 0.489362 (-7025 4825);
PAINT SKYBLUE (-7025 4825);
DISPLAY INVISIBLE (-7025 4825);
FORCEPROP 1 LAST WATTAGE 1/16W
J 0
(-6775 4775);
DISPLAY 0.489362 (-6775 4775);
PAINT SKYBLUE (-6775 4775);
DISPLAY INVISIBLE (-6775 4775);
FORCEPROP 2 LAST CDS_LIB pure_quanta
J 0
(-6850 4850);
DISPLAY INVISIBLE (-6850 4850);
FORCEPROP 2 LAST BOM_COST MEM
J 0
(-6875 5000);
DISPLAY 0.744681 (-6875 5000);
PAINT WHITE (-6875 5000);
DISPLAY INVISIBLE (-6875 5000);
FORCEPROP 1 LAST PATH I51
J 2
(-6800 5000);
DISPLAY 0.978723 (-6800 5000);
PAINT WHITE (-6800 5000);
DISPLAY INVISIBLE (-6800 5000);
FORCEPROP 1 LAST PART_NUMBER CS03302JB10
J 0
(-6950 4900);
DISPLAY 0.489362 (-6950 4900);
PAINT SKYBLUE (-6950 4900);
DISPLAY INVISIBLE (-6950 4900);
FORCEADD Q_RES..1
R 2
(-6850 4900);
FORCEPROP 1 LAST LOCATION R171
J 0
(-7075 4900);
DISPLAY 0.489362 (-7075 4900);
PAINT SKYBLUE (-7075 4900);
FORCEPROP 0 LAST $SEC 1
J 0
(-6950 4950);
DISPLAY 0.680851 (-6950 4950);
PAINT MONO (-6950 4950);
DISPLAY INVISIBLE (-6950 4950);
FORCEPROP 0 LAST CDS_SEC 1
J 0
(-6950 4950);
DISPLAY 1.021277 (-6950 4950);
DISPLAY INVISIBLE (-6950 4950);
FORCEPROP 1 LASTPIN (-6750 4900) $PN 1
J 2
(-6762 4912);
DISPLAY 0.489362 (-6762 4912);
PAINT MONO (-6762 4912);
FORCEPROP 1 LASTPIN (-6950 4900) $PN 2
J 2
(-6912 4912);
DISPLAY 0.489362 (-6912 4912);
PAINT MONO (-6912 4912);
FORCEPROP 1 LAST VALUE 33
J 0
(-6725 4900);
DISPLAY 0.489362 (-6725 4900);
PAINT SKYBLUE (-6725 4900);
FORCEPROP 1 LAST PACK_TYPE 0402LF
J 0
(-7025 4825);
DISPLAY 0.489362 (-7025 4825);
PAINT SKYBLUE (-7025 4825);
DISPLAY INVISIBLE (-7025 4825);
FORCEPROP 1 LAST TOLERANCE 5%
J 2
(-6725 4875);
DISPLAY 0.489362 (-6725 4875);
PAINT SKYBLUE (-6725 4875);
DISPLAY INVISIBLE (-6725 4875);
FORCEPROP 1 LAST MATERIAL CHIP
J 0
(-7025 4875);
DISPLAY 0.489362 (-7025 4875);
PAINT SKYBLUE (-7025 4875);
DISPLAY INVISIBLE (-7025 4875);
FORCEPROP 1 LAST WATTAGE 1/16W
J 0
(-6775 4825);
DISPLAY 0.489362 (-6775 4825);
PAINT SKYBLUE (-6775 4825);
DISPLAY INVISIBLE (-6775 4825);
FORCEPROP 2 LAST BOM_COST MEM
J 0
(-6875 5050);
DISPLAY 0.744681 (-6875 5050);
PAINT WHITE (-6875 5050);
DISPLAY INVISIBLE (-6875 5050);
FORCEPROP 2 LAST CDS_LIB pure_quanta
J 0
(-6850 4900);
DISPLAY INVISIBLE (-6850 4900);
FORCEPROP 1 LAST PATH I52
J 2
(-6800 5050);
DISPLAY 0.978723 (-6800 5050);
PAINT WHITE (-6800 5050);
DISPLAY INVISIBLE (-6800 5050);
FORCEPROP 1 LAST PART_NUMBER CS03302JB10
J 0
(-6950 4950);
DISPLAY 0.489362 (-6950 4950);
PAINT SKYBLUE (-6950 4950);
DISPLAY INVISIBLE (-6950 4950);
FORCEADD Q_RES..1
R 2
(-6850 4950);
FORCEPROP 1 LAST LOCATION R170
J 0
(-7075 4950);
DISPLAY 0.489362 (-7075 4950);
PAINT SKYBLUE (-7075 4950);
FORCEPROP 0 LAST $SEC 1
J 0
(-6950 5000);
DISPLAY 0.680851 (-6950 5000);
PAINT MONO (-6950 5000);
DISPLAY INVISIBLE (-6950 5000);
FORCEPROP 0 LAST CDS_SEC 1
J 0
(-6950 5000);
DISPLAY 1.021277 (-6950 5000);
DISPLAY INVISIBLE (-6950 5000);
FORCEPROP 1 LASTPIN (-6750 4950) $PN 1
J 2
(-6762 4962);
DISPLAY 0.489362 (-6762 4962);
PAINT MONO (-6762 4962);
FORCEPROP 1 LASTPIN (-6950 4950) $PN 2
J 2
(-6912 4962);
DISPLAY 0.489362 (-6912 4962);
PAINT MONO (-6912 4962);
FORCEPROP 1 LAST VALUE 33
J 0
(-6725 4950);
DISPLAY 0.489362 (-6725 4950);
PAINT SKYBLUE (-6725 4950);
FORCEPROP 1 LAST PACK_TYPE 0402LF
J 0
(-7025 4875);
DISPLAY 0.489362 (-7025 4875);
PAINT SKYBLUE (-7025 4875);
DISPLAY INVISIBLE (-7025 4875);
FORCEPROP 1 LAST TOLERANCE 5%
J 2
(-6725 4925);
DISPLAY 0.489362 (-6725 4925);
PAINT SKYBLUE (-6725 4925);
DISPLAY INVISIBLE (-6725 4925);
FORCEPROP 1 LAST MATERIAL CHIP
J 0
(-7025 4925);
DISPLAY 0.489362 (-7025 4925);
PAINT SKYBLUE (-7025 4925);
DISPLAY INVISIBLE (-7025 4925);
FORCEPROP 1 LAST WATTAGE 1/16W
J 0
(-6775 4875);
DISPLAY 0.489362 (-6775 4875);
PAINT SKYBLUE (-6775 4875);
DISPLAY INVISIBLE (-6775 4875);
FORCEPROP 2 LAST BOM_COST MEM
J 0
(-6875 5100);
DISPLAY 0.744681 (-6875 5100);
PAINT WHITE (-6875 5100);
DISPLAY INVISIBLE (-6875 5100);
FORCEPROP 2 LAST CDS_LIB pure_quanta
J 0
(-6850 4950);
DISPLAY INVISIBLE (-6850 4950);
FORCEPROP 1 LAST PATH I53
J 2
(-6800 5100);
DISPLAY 0.978723 (-6800 5100);
PAINT WHITE (-6800 5100);
DISPLAY INVISIBLE (-6800 5100);
FORCEPROP 1 LAST PART_NUMBER CS03302JB10
J 0
(-6950 5000);
DISPLAY 0.489362 (-6950 5000);
PAINT SKYBLUE (-6950 5000);
DISPLAY INVISIBLE (-6950 5000);
FORCEADD Q_RES..1
R 2
(-6850 5000);
FORCEPROP 1 LAST LOCATION R163
J 0
(-7075 5000);
DISPLAY 0.489362 (-7075 5000);
PAINT SKYBLUE (-7075 5000);
FORCEPROP 0 LAST $SEC 1
J 0
(-6975 5050);
DISPLAY 0.680851 (-6975 5050);
PAINT MONO (-6975 5050);
DISPLAY INVISIBLE (-6975 5050);
FORCEPROP 0 LAST CDS_SEC 1
J 0
(-6975 5050);
DISPLAY 1.021277 (-6975 5050);
DISPLAY INVISIBLE (-6975 5050);
FORCEPROP 1 LASTPIN (-6750 5000) $PN 1
J 2
(-6762 5012);
DISPLAY 0.489362 (-6762 5012);
PAINT MONO (-6762 5012);
FORCEPROP 1 LASTPIN (-6950 5000) $PN 2
J 2
(-6912 5012);
DISPLAY 0.489362 (-6912 5012);
PAINT MONO (-6912 5012);
FORCEPROP 1 LAST VALUE 33
J 0
(-6725 5000);
DISPLAY 0.489362 (-6725 5000);
PAINT SKYBLUE (-6725 5000);
FORCEPROP 1 LAST PACK_TYPE 0402LF
J 0
(-7025 4925);
DISPLAY 0.489362 (-7025 4925);
PAINT SKYBLUE (-7025 4925);
DISPLAY INVISIBLE (-7025 4925);
FORCEPROP 1 LAST TOLERANCE 5%
J 2
(-6725 4975);
DISPLAY 0.489362 (-6725 4975);
PAINT SKYBLUE (-6725 4975);
DISPLAY INVISIBLE (-6725 4975);
FORCEPROP 1 LAST MATERIAL CHIP
J 0
(-7025 4975);
DISPLAY 0.489362 (-7025 4975);
PAINT SKYBLUE (-7025 4975);
DISPLAY INVISIBLE (-7025 4975);
FORCEPROP 1 LAST WATTAGE 1/16W
J 0
(-6775 4925);
DISPLAY 0.489362 (-6775 4925);
PAINT SKYBLUE (-6775 4925);
DISPLAY INVISIBLE (-6775 4925);
FORCEPROP 2 LAST CDS_LIB pure_quanta
J 0
(-6850 5000);
DISPLAY INVISIBLE (-6850 5000);
FORCEPROP 2 LAST BOM_COST MEM
J 0
(-6875 5150);
DISPLAY 0.744681 (-6875 5150);
PAINT WHITE (-6875 5150);
DISPLAY INVISIBLE (-6875 5150);
FORCEPROP 1 LAST PATH I54
J 2
(-6800 5150);
DISPLAY 0.978723 (-6800 5150);
PAINT WHITE (-6800 5150);
DISPLAY INVISIBLE (-6800 5150);
FORCEPROP 1 LAST PART_NUMBER CS03302JB10
J 0
(-6950 5050);
DISPLAY 0.489362 (-6950 5050);
PAINT SKYBLUE (-6950 5050);
DISPLAY INVISIBLE (-6950 5050);
FORCEADD Q_RES..1
R 2
(-3825 1100);
FORCEPROP 1 LAST LOCATION R6031
J 0
(-4025 1100);
DISPLAY 0.489362 (-4025 1100);
PAINT SKYBLUE (-4025 1100);
FORCEPROP 0 LAST $SEC 1
J 0
(-3700 1125);
DISPLAY 0.680851 (-3700 1125);
PAINT MONO (-3700 1125);
DISPLAY INVISIBLE (-3700 1125);
FORCEPROP 0 LAST CDS_SEC 1
J 0
(-3700 1125);
DISPLAY 0.680851 (-3700 1125);
DISPLAY INVISIBLE (-3700 1125);
FORCEPROP 1 LASTPIN (-3725 1100) $PN 1
J 2
(-3737 1112);
DISPLAY 0.787234 (-3737 1112);
PAINT MONO (-3737 1112);
FORCEPROP 1 LASTPIN (-3925 1100) $PN 2
J 2
(-3887 1112);
DISPLAY 0.787234 (-3887 1112);
PAINT MONO (-3887 1112);
FORCEPROP 1 LAST VALUE 33
J 0
(-3700 1100);
DISPLAY 0.489362 (-3700 1100);
PAINT SKYBLUE (-3700 1100);
FORCEPROP 2 LAST BOM_COST MEM
J 0
(-3850 1250);
DISPLAY 0.744681 (-3850 1250);
PAINT WHITE (-3850 1250);
DISPLAY INVISIBLE (-3850 1250);
FORCEPROP 1 LAST WATTAGE 1/16W
J 0
(-3750 1025);
DISPLAY 0.489362 (-3750 1025);
PAINT SKYBLUE (-3750 1025);
DISPLAY INVISIBLE (-3750 1025);
FORCEPROP 1 LAST MATERIAL CHIP
J 0
(-4000 1075);
DISPLAY 0.489362 (-4000 1075);
PAINT SKYBLUE (-4000 1075);
DISPLAY INVISIBLE (-4000 1075);
FORCEPROP 1 LAST TOLERANCE 5%
J 2
(-3700 1075);
DISPLAY 0.489362 (-3700 1075);
PAINT SKYBLUE (-3700 1075);
DISPLAY INVISIBLE (-3700 1075);
FORCEPROP 1 LAST PACK_TYPE 0402LF
J 0
(-4000 1025);
DISPLAY 0.489362 (-4000 1025);
PAINT SKYBLUE (-4000 1025);
DISPLAY INVISIBLE (-4000 1025);
FORCEPROP 2 LAST CDS_LIB pure_quanta
J 0
(-3825 1100);
DISPLAY INVISIBLE (-3825 1100);
FORCEPROP 1 LAST PATH I55
J 2
(-3775 1250);
DISPLAY 0.978723 (-3775 1250);
PAINT WHITE (-3775 1250);
DISPLAY INVISIBLE (-3775 1250);
FORCEPROP 1 LAST PART_NUMBER CS03302JB10
J 0
(-3925 1150);
DISPLAY 0.489362 (-3925 1150);
PAINT SKYBLUE (-3925 1150);
DISPLAY INVISIBLE (-3925 1150);
FORCEADD OFFPAGE..2
(-2825 1100);
FORCEPROP 2 LAST $XR0 152 
J 0
(-2636 1100);
DISPLAY 0.638298 (-2636 1100);
PAINT MONO (-2636 1100);
FORCEPROP 2 LAST CDS_LIB standard
J 0
(-2825 1100);
DISPLAY INVISIBLE (-2825 1100);
FORCEPROP 1 LAST OFFPAGE TRUE
J 0
(-2500 975);
DISPLAY 0.872340 (-2500 975);
PAINT GREEN (-2500 975);
DISPLAY INVISIBLE (-2500 975);
FORCEPROP 1 LAST COMMENT_BODY TRUE
J 0
(-2870 1005);
DISPLAY 0.872340 (-2870 1005);
PAINT GREEN (-2870 1005);
DISPLAY INVISIBLE (-2870 1005);
FORCEPROP 2 LAST PATH I56
J 0
(-2650 1175);
DISPLAY 0.680851 (-2650 1175);
DISPLAY INVISIBLE (-2650 1175);
FORCEADD OFFPAGE..1
R 2
(-2825 1200);
FORCEPROP 2 LAST $XR0 83 
J 0
(-2639 1200);
DISPLAY 0.638298 (-2639 1200);
PAINT MONO (-2639 1200);
FORCEPROP 2 LAST CDS_LIB standard
J 0
(-2825 1200);
DISPLAY INVISIBLE (-2825 1200);
FORCEPROP 1 LAST OFFPAGE TRUE
J 2
(-3150 1075);
DISPLAY 0.872340 (-3150 1075);
PAINT GREEN (-3150 1075);
DISPLAY INVISIBLE (-3150 1075);
FORCEPROP 1 LAST COMMENT_BODY TRUE
J 2
(-2950 1100);
DISPLAY 0.872340 (-2950 1100);
PAINT GREEN (-2950 1100);
DISPLAY INVISIBLE (-2950 1100);
FORCEPROP 2 LAST PATH I57
J 0
(-2625 1250);
DISPLAY 0.680851 (-2625 1250);
DISPLAY INVISIBLE (-2625 1250);
FORCEADD OFFPAGE..4
(-2825 1150);
FORCEPROP 2 LAST $XR0 150 
J 0
(-2639 1150);
DISPLAY 0.638298 (-2639 1150);
PAINT MONO (-2639 1150);
FORCEPROP 2 LAST CDS_LIB standard
J 0
(-2825 1150);
DISPLAY INVISIBLE (-2825 1150);
FORCEPROP 1 LAST OFFPAGE TRUE
J 0
(-2500 1025);
DISPLAY 0.872340 (-2500 1025);
DISPLAY INVISIBLE (-2500 1025);
FORCEPROP 1 LAST COMMENT_BODY TRUE
J 0
(-2850 1050);
DISPLAY 0.872340 (-2850 1050);
PAINT GREEN (-2850 1050);
DISPLAY INVISIBLE (-2850 1050);
FORCEPROP 2 LAST PATH I58
J 0
(-2650 1225);
DISPLAY 0.680851 (-2650 1225);
DISPLAY INVISIBLE (-2650 1225);
FORCEADD OFFPAGE..1
R 2
(-2825 1250);
FORCEPROP 2 LAST $XR0 83 
J 0
(-2639 1250);
DISPLAY 0.638298 (-2639 1250);
PAINT MONO (-2639 1250);
FORCEPROP 2 LAST CDS_LIB standard
J 0
(-2825 1250);
DISPLAY INVISIBLE (-2825 1250);
FORCEPROP 1 LAST OFFPAGE TRUE
J 2
(-3150 1125);
DISPLAY 0.872340 (-3150 1125);
PAINT GREEN (-3150 1125);
DISPLAY INVISIBLE (-3150 1125);
FORCEPROP 1 LAST COMMENT_BODY TRUE
J 2
(-2950 1150);
DISPLAY 0.872340 (-2950 1150);
PAINT GREEN (-2950 1150);
DISPLAY INVISIBLE (-2950 1150);
FORCEPROP 2 LAST PATH I59
J 0
(-2625 1300);
DISPLAY 0.680851 (-2625 1300);
DISPLAY INVISIBLE (-2625 1300);
FORCEADD OFFPAGE..2
R 2
(-7875 3150);
FORCEPROP 2 LAST $XR0 145 
J 0
(-8130 3150);
DISPLAY 0.638298 (-8130 3150);
PAINT MONO (-8130 3150);
FORCEPROP 2 LAST CDS_LIB standard
J 0
(-7875 3150);
DISPLAY INVISIBLE (-7875 3150);
FORCEPROP 1 LAST OFFPAGE TRUE
J 2
(-8200 3025);
DISPLAY 0.872340 (-8200 3025);
PAINT GREEN (-8200 3025);
DISPLAY INVISIBLE (-8200 3025);
FORCEPROP 1 LAST COMMENT_BODY TRUE
J 2
(-7830 3055);
DISPLAY 0.872340 (-7830 3055);
PAINT GREEN (-7830 3055);
DISPLAY INVISIBLE (-7830 3055);
FORCEPROP 2 LAST PATH I6
J 0
(-8150 3200);
DISPLAY 0.680851 (-8150 3200);
DISPLAY INVISIBLE (-8150 3200);
FORCEADD OFFPAGE..1
R 2
(-2825 1350);
FORCEPROP 2 LAST $XR1 171 
J 0
(-2549 1350);
DISPLAY 0.638298 (-2549 1350);
PAINT MONO (-2549 1350);
FORCEPROP 2 LAST $XR0 85 
J 0
(-2639 1350);
DISPLAY 0.638298 (-2639 1350);
PAINT MONO (-2639 1350);
FORCEPROP 2 LAST CDS_LIB standard
J 0
(-2825 1350);
DISPLAY INVISIBLE (-2825 1350);
FORCEPROP 1 LAST OFFPAGE TRUE
J 2
(-3150 1225);
DISPLAY 0.872340 (-3150 1225);
PAINT GREEN (-3150 1225);
DISPLAY INVISIBLE (-3150 1225);
FORCEPROP 1 LAST COMMENT_BODY TRUE
J 2
(-2950 1250);
DISPLAY 0.872340 (-2950 1250);
PAINT GREEN (-2950 1250);
DISPLAY INVISIBLE (-2950 1250);
FORCEPROP 2 LAST PATH I60
J 0
(-2525 1400);
DISPLAY 0.680851 (-2525 1400);
DISPLAY INVISIBLE (-2525 1400);
FORCEADD OFFPAGE..1
R 2
(-2825 1300);
FORCEPROP 2 LAST $XR1 171 
J 0
(-2549 1300);
DISPLAY 0.638298 (-2549 1300);
PAINT MONO (-2549 1300);
FORCEPROP 2 LAST $XR0 85 
J 0
(-2639 1300);
DISPLAY 0.638298 (-2639 1300);
PAINT MONO (-2639 1300);
FORCEPROP 2 LAST CDS_LIB standard
J 0
(-2825 1300);
DISPLAY INVISIBLE (-2825 1300);
FORCEPROP 1 LAST OFFPAGE TRUE
J 2
(-3150 1175);
DISPLAY 0.872340 (-3150 1175);
PAINT GREEN (-3150 1175);
DISPLAY INVISIBLE (-3150 1175);
FORCEPROP 1 LAST COMMENT_BODY TRUE
J 2
(-2950 1200);
DISPLAY 0.872340 (-2950 1200);
PAINT GREEN (-2950 1200);
DISPLAY INVISIBLE (-2950 1200);
FORCEPROP 2 LAST PATH I61
J 0
(-2525 1350);
DISPLAY 0.680851 (-2525 1350);
DISPLAY INVISIBLE (-2525 1350);
FORCEADD OFFPAGE..1
R 2
(-2825 1400);
FORCEPROP 2 LAST $XR1 171 
J 0
(-2549 1400);
DISPLAY 0.638298 (-2549 1400);
PAINT MONO (-2549 1400);
FORCEPROP 2 LAST $XR0 85 
J 0
(-2639 1400);
DISPLAY 0.638298 (-2639 1400);
PAINT MONO (-2639 1400);
FORCEPROP 2 LAST CDS_LIB standard
J 0
(-2825 1400);
DISPLAY INVISIBLE (-2825 1400);
FORCEPROP 1 LAST OFFPAGE TRUE
J 2
(-3150 1275);
DISPLAY 0.872340 (-3150 1275);
PAINT GREEN (-3150 1275);
DISPLAY INVISIBLE (-3150 1275);
FORCEPROP 1 LAST COMMENT_BODY TRUE
J 2
(-2950 1300);
DISPLAY 0.872340 (-2950 1300);
PAINT GREEN (-2950 1300);
DISPLAY INVISIBLE (-2950 1300);
FORCEPROP 2 LAST PATH I62
J 0
(-2525 1450);
DISPLAY 0.680851 (-2525 1450);
DISPLAY INVISIBLE (-2525 1450);
FORCEADD OFFPAGE..2
(-2825 1450);
FORCEPROP 2 LAST $XR1 171 
J 0
(-2546 1450);
DISPLAY 0.638298 (-2546 1450);
PAINT MONO (-2546 1450);
FORCEPROP 2 LAST $XR0 85 
J 0
(-2636 1450);
DISPLAY 0.638298 (-2636 1450);
PAINT MONO (-2636 1450);
FORCEPROP 2 LAST CDS_LIB standard
J 0
(-2825 1450);
DISPLAY INVISIBLE (-2825 1450);
FORCEPROP 1 LAST OFFPAGE TRUE
J 0
(-2500 1325);
DISPLAY 0.872340 (-2500 1325);
PAINT GREEN (-2500 1325);
DISPLAY INVISIBLE (-2500 1325);
FORCEPROP 1 LAST COMMENT_BODY TRUE
J 0
(-2870 1355);
DISPLAY 0.872340 (-2870 1355);
PAINT GREEN (-2870 1355);
DISPLAY INVISIBLE (-2870 1355);
FORCEPROP 2 LAST PATH I63
J 0
(-2525 1500);
DISPLAY 0.680851 (-2525 1500);
DISPLAY INVISIBLE (-2525 1500);
FORCEADD Q_RES..1
R 2
(-2775 2850);
FORCEPROP 1 LAST LOCATION R6030
J 0
(-2975 2850);
DISPLAY 0.489362 (-2975 2850);
PAINT SKYBLUE (-2975 2850);
FORCEPROP 0 LAST $SEC 1
J 0
(-2650 2875);
DISPLAY 0.680851 (-2650 2875);
PAINT MONO (-2650 2875);
DISPLAY INVISIBLE (-2650 2875);
FORCEPROP 0 LAST CDS_SEC 1
J 0
(-2650 2875);
DISPLAY 0.680851 (-2650 2875);
DISPLAY INVISIBLE (-2650 2875);
FORCEPROP 1 LASTPIN (-2675 2850) $PN 1
J 2
(-2687 2862);
DISPLAY 0.787234 (-2687 2862);
PAINT MONO (-2687 2862);
FORCEPROP 1 LASTPIN (-2875 2850) $PN 2
J 2
(-2837 2862);
DISPLAY 0.787234 (-2837 2862);
PAINT MONO (-2837 2862);
FORCEPROP 1 LAST VALUE 33
J 0
(-2650 2850);
DISPLAY 0.489362 (-2650 2850);
PAINT SKYBLUE (-2650 2850);
FORCEPROP 2 LAST CDS_LIB pure_quanta
J 0
(-2775 2850);
DISPLAY INVISIBLE (-2775 2850);
FORCEPROP 1 LAST PACK_TYPE 0402LF
J 0
(-2950 2775);
DISPLAY 0.489362 (-2950 2775);
PAINT SKYBLUE (-2950 2775);
DISPLAY INVISIBLE (-2950 2775);
FORCEPROP 1 LAST TOLERANCE 5%
J 2
(-2650 2825);
DISPLAY 0.489362 (-2650 2825);
PAINT SKYBLUE (-2650 2825);
DISPLAY INVISIBLE (-2650 2825);
FORCEPROP 1 LAST MATERIAL CHIP
J 0
(-2950 2825);
DISPLAY 0.489362 (-2950 2825);
PAINT SKYBLUE (-2950 2825);
DISPLAY INVISIBLE (-2950 2825);
FORCEPROP 1 LAST WATTAGE 1/16W
J 0
(-2700 2775);
DISPLAY 0.489362 (-2700 2775);
PAINT SKYBLUE (-2700 2775);
DISPLAY INVISIBLE (-2700 2775);
FORCEPROP 2 LAST BOM_COST MEM
J 0
(-2800 3000);
DISPLAY 0.744681 (-2800 3000);
PAINT WHITE (-2800 3000);
DISPLAY INVISIBLE (-2800 3000);
FORCEPROP 1 LAST PATH I64
J 2
(-2725 3000);
DISPLAY 0.978723 (-2725 3000);
PAINT WHITE (-2725 3000);
DISPLAY INVISIBLE (-2725 3000);
FORCEPROP 1 LAST PART_NUMBER CS03302JB10
J 0
(-2875 2900);
DISPLAY 0.489362 (-2875 2900);
PAINT SKYBLUE (-2875 2900);
DISPLAY INVISIBLE (-2875 2900);
FORCEADD Q_RES..1
R 2
(-2775 2900);
FORCEPROP 1 LAST LOCATION R6029
J 0
(-2975 2900);
DISPLAY 0.489362 (-2975 2900);
PAINT SKYBLUE (-2975 2900);
FORCEPROP 0 LAST $SEC 1
J 0
(-2650 2925);
DISPLAY 0.680851 (-2650 2925);
PAINT MONO (-2650 2925);
DISPLAY INVISIBLE (-2650 2925);
FORCEPROP 0 LAST CDS_SEC 1
J 0
(-2650 2925);
DISPLAY 0.680851 (-2650 2925);
DISPLAY INVISIBLE (-2650 2925);
FORCEPROP 1 LASTPIN (-2675 2900) $PN 1
J 2
(-2687 2912);
DISPLAY 0.787234 (-2687 2912);
PAINT MONO (-2687 2912);
FORCEPROP 1 LASTPIN (-2875 2900) $PN 2
J 2
(-2837 2912);
DISPLAY 0.787234 (-2837 2912);
PAINT MONO (-2837 2912);
FORCEPROP 1 LAST VALUE 33
J 0
(-2650 2900);
DISPLAY 0.489362 (-2650 2900);
PAINT SKYBLUE (-2650 2900);
FORCEPROP 2 LAST CDS_LIB pure_quanta
J 0
(-2775 2900);
DISPLAY INVISIBLE (-2775 2900);
FORCEPROP 2 LAST BOM_COST MEM
J 0
(-2800 3050);
DISPLAY 0.744681 (-2800 3050);
PAINT WHITE (-2800 3050);
DISPLAY INVISIBLE (-2800 3050);
FORCEPROP 1 LAST WATTAGE 1/16W
J 0
(-2700 2825);
DISPLAY 0.489362 (-2700 2825);
PAINT SKYBLUE (-2700 2825);
DISPLAY INVISIBLE (-2700 2825);
FORCEPROP 1 LAST MATERIAL CHIP
J 0
(-2950 2875);
DISPLAY 0.489362 (-2950 2875);
PAINT SKYBLUE (-2950 2875);
DISPLAY INVISIBLE (-2950 2875);
FORCEPROP 1 LAST TOLERANCE 5%
J 2
(-2650 2875);
DISPLAY 0.489362 (-2650 2875);
PAINT SKYBLUE (-2650 2875);
DISPLAY INVISIBLE (-2650 2875);
FORCEPROP 1 LAST PACK_TYPE 0402LF
J 0
(-2950 2825);
DISPLAY 0.489362 (-2950 2825);
PAINT SKYBLUE (-2950 2825);
DISPLAY INVISIBLE (-2950 2825);
FORCEPROP 1 LAST PATH I65
J 2
(-2725 3050);
DISPLAY 0.978723 (-2725 3050);
PAINT WHITE (-2725 3050);
DISPLAY INVISIBLE (-2725 3050);
FORCEPROP 1 LAST PART_NUMBER CS03302JB10
J 0
(-2875 2950);
DISPLAY 0.489362 (-2875 2950);
PAINT SKYBLUE (-2875 2950);
DISPLAY INVISIBLE (-2875 2950);
FORCEADD OFFPAGE..4
(-1775 2700);
FORCEPROP 2 LAST $XR1 138 
J 0
(-1469 2700);
DISPLAY 0.638298 (-1469 2700);
PAINT MONO (-1469 2700);
FORCEPROP 2 LAST $XR0 137 
J 0
(-1589 2700);
DISPLAY 0.638298 (-1589 2700);
PAINT MONO (-1589 2700);
FORCEPROP 2 LAST CDS_LIB standard
J 2
(-1775 2700);
DISPLAY INVISIBLE (-1775 2700);
FORCEPROP 1 LAST OFFPAGE TRUE
J 0
(-1450 2575);
DISPLAY 0.872340 (-1450 2575);
DISPLAY INVISIBLE (-1450 2575);
FORCEPROP 1 LAST COMMENT_BODY TRUE
J 0
(-1800 2600);
DISPLAY 0.872340 (-1800 2600);
PAINT GREEN (-1800 2600);
DISPLAY INVISIBLE (-1800 2600);
FORCEPROP 2 LAST PATH I66
J 2
(-1950 2775);
DISPLAY 0.680851 (-1950 2775);
DISPLAY INVISIBLE (-1950 2775);
FORCEADD OFFPAGE..2
(-1775 2750);
FORCEPROP 2 LAST $XR0 249 
J 0
(-1586 2750);
DISPLAY 0.638298 (-1586 2750);
PAINT MONO (-1586 2750);
FORCEPROP 2 LAST CDS_LIB standard
J 0
(-1775 2750);
DISPLAY INVISIBLE (-1775 2750);
FORCEPROP 1 LAST OFFPAGE TRUE
J 0
(-1450 2625);
DISPLAY 0.872340 (-1450 2625);
PAINT GREEN (-1450 2625);
DISPLAY INVISIBLE (-1450 2625);
FORCEPROP 1 LAST COMMENT_BODY TRUE
J 0
(-1820 2655);
DISPLAY 0.872340 (-1820 2655);
PAINT GREEN (-1820 2655);
DISPLAY INVISIBLE (-1820 2655);
FORCEPROP 2 LAST PATH I67
J 0
(-1600 2825);
DISPLAY 0.680851 (-1600 2825);
DISPLAY INVISIBLE (-1600 2825);
FORCEADD OFFPAGE..2
(-1775 2850);
FORCEPROP 2 LAST $XR0 234 
J 0
(-1586 2850);
DISPLAY 0.638298 (-1586 2850);
PAINT MONO (-1586 2850);
FORCEPROP 2 LAST CDS_LIB standard
J 0
(-1775 2850);
DISPLAY INVISIBLE (-1775 2850);
FORCEPROP 1 LAST OFFPAGE TRUE
J 0
(-1450 2725);
DISPLAY 0.872340 (-1450 2725);
PAINT GREEN (-1450 2725);
DISPLAY INVISIBLE (-1450 2725);
FORCEPROP 1 LAST COMMENT_BODY TRUE
J 0
(-1820 2755);
DISPLAY 0.872340 (-1820 2755);
PAINT GREEN (-1820 2755);
DISPLAY INVISIBLE (-1820 2755);
FORCEPROP 2 LAST PATH I68
J 0
(-1600 2925);
DISPLAY 0.680851 (-1600 2925);
DISPLAY INVISIBLE (-1600 2925);
FORCEADD OFFPAGE..2
(-1775 2900);
FORCEPROP 2 LAST $XR0 234 
J 0
(-1586 2900);
DISPLAY 0.638298 (-1586 2900);
PAINT MONO (-1586 2900);
FORCEPROP 2 LAST CDS_LIB standard
J 0
(-1775 2900);
DISPLAY INVISIBLE (-1775 2900);
FORCEPROP 1 LAST OFFPAGE TRUE
J 0
(-1450 2775);
DISPLAY 0.872340 (-1450 2775);
PAINT GREEN (-1450 2775);
DISPLAY INVISIBLE (-1450 2775);
FORCEPROP 1 LAST COMMENT_BODY TRUE
J 0
(-1820 2805);
DISPLAY 0.872340 (-1820 2805);
PAINT GREEN (-1820 2805);
DISPLAY INVISIBLE (-1820 2805);
FORCEPROP 2 LAST PATH I69
J 0
(-1600 2975);
DISPLAY 0.680851 (-1600 2975);
DISPLAY INVISIBLE (-1600 2975);
FORCEADD OFFPAGE..4
R 2
(-7875 3100);
FORCEPROP 2 LAST $XR0 269 
J 0
(-8127 3100);
DISPLAY 0.638298 (-8127 3100);
PAINT MONO (-8127 3100);
FORCEPROP 2 LAST CDS_LIB standard
J 0
(-7875 3100);
DISPLAY INVISIBLE (-7875 3100);
FORCEPROP 1 LAST OFFPAGE TRUE
J 2
(-8200 2975);
DISPLAY 0.872340 (-8200 2975);
PAINT GREEN (-8200 2975);
DISPLAY INVISIBLE (-8200 2975);
FORCEPROP 1 LAST COMMENT_BODY TRUE
J 2
(-7850 3000);
DISPLAY 0.872340 (-7850 3000);
PAINT GREEN (-7850 3000);
DISPLAY INVISIBLE (-7850 3000);
FORCEPROP 2 LAST PATH I7
J 0
(-8150 3150);
DISPLAY 0.680851 (-8150 3150);
DISPLAY INVISIBLE (-8150 3150);
FORCEADD OFFPAGE..1
R 2
(-1775 2950);
FORCEPROP 2 LAST $XR1 268 
J 0
(-1469 2950);
DISPLAY 0.638298 (-1469 2950);
PAINT MONO (-1469 2950);
FORCEPROP 2 LAST $XR0 263 
J 0
(-1589 2950);
DISPLAY 0.638298 (-1589 2950);
PAINT MONO (-1589 2950);
FORCEPROP 2 LAST CDS_LIB standard
J 0
(-1775 2950);
DISPLAY INVISIBLE (-1775 2950);
FORCEPROP 1 LAST OFFPAGE TRUE
J 2
(-2100 2825);
DISPLAY 0.872340 (-2100 2825);
PAINT GREEN (-2100 2825);
DISPLAY INVISIBLE (-2100 2825);
FORCEPROP 1 LAST COMMENT_BODY TRUE
J 2
(-1900 2850);
DISPLAY 0.872340 (-1900 2850);
PAINT GREEN (-1900 2850);
DISPLAY INVISIBLE (-1900 2850);
FORCEPROP 2 LAST PATH I70
J 0
(-1600 3025);
DISPLAY 0.680851 (-1600 3025);
DISPLAY INVISIBLE (-1600 3025);
FORCEADD OFFPAGE..1
R 2
(-1775 3200);
FORCEPROP 2 LAST $XR0 150 
J 0
(-1589 3200);
DISPLAY 0.638298 (-1589 3200);
PAINT MONO (-1589 3200);
FORCEPROP 2 LAST CDS_LIB standard
J 0
(-1775 3200);
DISPLAY INVISIBLE (-1775 3200);
FORCEPROP 1 LAST OFFPAGE TRUE
J 2
(-2100 3075);
DISPLAY 0.872340 (-2100 3075);
PAINT GREEN (-2100 3075);
DISPLAY INVISIBLE (-2100 3075);
FORCEPROP 1 LAST COMMENT_BODY TRUE
J 2
(-1900 3100);
DISPLAY 0.872340 (-1900 3100);
PAINT GREEN (-1900 3100);
DISPLAY INVISIBLE (-1900 3100);
FORCEPROP 2 LAST PATH I71
J 0
(-1600 3275);
DISPLAY 0.680851 (-1600 3275);
DISPLAY INVISIBLE (-1600 3275);
FORCEADD OFFPAGE..2
(-1775 3100);
FORCEPROP 2 LAST $XR0 150 
J 0
(-1586 3100);
DISPLAY 0.638298 (-1586 3100);
PAINT MONO (-1586 3100);
FORCEPROP 2 LAST CDS_LIB standard
J 2
(-1775 3100);
DISPLAY INVISIBLE (-1775 3100);
FORCEPROP 1 LAST OFFPAGE TRUE
J 0
(-1450 2975);
DISPLAY 0.872340 (-1450 2975);
DISPLAY INVISIBLE (-1450 2975);
FORCEPROP 1 LAST COMMENT_BODY TRUE
J 0
(-1820 3005);
DISPLAY 0.872340 (-1820 3005);
PAINT GREEN (-1820 3005);
DISPLAY INVISIBLE (-1820 3005);
FORCEPROP 2 LAST PATH I72
J 0
(-1600 3175);
DISPLAY 0.680851 (-1600 3175);
DISPLAY INVISIBLE (-1600 3175);
FORCEADD OFFPAGE..1
R 2
(-1775 3350);
FORCEPROP 2 LAST $XR1 151 
J 0
(-1469 3350);
DISPLAY 0.638298 (-1469 3350);
PAINT MONO (-1469 3350);
FORCEPROP 2 LAST $XR0 150 
J 0
(-1589 3350);
DISPLAY 0.638298 (-1589 3350);
PAINT MONO (-1589 3350);
FORCEPROP 2 LAST CDS_LIB standard
J 0
(-1775 3350);
DISPLAY INVISIBLE (-1775 3350);
FORCEPROP 1 LAST OFFPAGE TRUE
J 2
(-2100 3225);
DISPLAY 0.872340 (-2100 3225);
PAINT GREEN (-2100 3225);
DISPLAY INVISIBLE (-2100 3225);
FORCEPROP 1 LAST COMMENT_BODY TRUE
J 2
(-1900 3250);
DISPLAY 0.872340 (-1900 3250);
PAINT GREEN (-1900 3250);
DISPLAY INVISIBLE (-1900 3250);
FORCEPROP 2 LAST PATH I73
J 0
(-1600 3425);
DISPLAY 0.680851 (-1600 3425);
DISPLAY INVISIBLE (-1600 3425);
FORCEADD OFFPAGE..2
(-1775 3550);
FORCEPROP 2 LAST $XR5 253 
J 0
(-986 3550);
DISPLAY 0.638298 (-986 3550);
PAINT MONO (-986 3550);
FORCEPROP 2 LAST $XR4 251 
J 0
(-1106 3550);
DISPLAY 0.638298 (-1106 3550);
PAINT MONO (-1106 3550);
FORCEPROP 2 LAST $XR3 246 
J 0
(-1226 3550);
DISPLAY 0.638298 (-1226 3550);
PAINT MONO (-1226 3550);
FORCEPROP 2 LAST $XR2 241 
J 0
(-1346 3550);
DISPLAY 0.638298 (-1346 3550);
PAINT MONO (-1346 3550);
FORCEPROP 2 LAST $XR1 139 
J 0
(-1466 3550);
DISPLAY 0.638298 (-1466 3550);
PAINT MONO (-1466 3550);
FORCEPROP 2 LAST $XR0 132 
J 0
(-1586 3550);
DISPLAY 0.638298 (-1586 3550);
PAINT MONO (-1586 3550);
FORCEPROP 2 LAST CDS_LIB standard
J 0
(-1775 3550);
DISPLAY INVISIBLE (-1775 3550);
FORCEPROP 1 LAST OFFPAGE TRUE
J 0
(-1450 3425);
DISPLAY 0.872340 (-1450 3425);
PAINT GREEN (-1450 3425);
DISPLAY INVISIBLE (-1450 3425);
FORCEPROP 1 LAST COMMENT_BODY TRUE
J 0
(-1820 3455);
DISPLAY 0.872340 (-1820 3455);
PAINT GREEN (-1820 3455);
DISPLAY INVISIBLE (-1820 3455);
FORCEPROP 2 LAST PATH I75
J 0
(-1600 3625);
DISPLAY 0.680851 (-1600 3625);
DISPLAY INVISIBLE (-1600 3625);
FORCEADD OFFPAGE..1
R 2
(-1775 3700);
FORCEPROP 2 LAST $XR0 210 
J 0
(-1589 3700);
DISPLAY 0.638298 (-1589 3700);
PAINT MONO (-1589 3700);
FORCEPROP 2 LAST CDS_LIB standard
J 0
(-1775 3700);
DISPLAY INVISIBLE (-1775 3700);
FORCEPROP 1 LAST OFFPAGE TRUE
J 2
(-2100 3575);
DISPLAY 0.872340 (-2100 3575);
PAINT GREEN (-2100 3575);
DISPLAY INVISIBLE (-2100 3575);
FORCEPROP 1 LAST COMMENT_BODY TRUE
J 2
(-1900 3600);
DISPLAY 0.872340 (-1900 3600);
PAINT GREEN (-1900 3600);
DISPLAY INVISIBLE (-1900 3600);
FORCEPROP 2 LAST PATH I76
J 0
(-1575 3750);
DISPLAY 0.680851 (-1575 3750);
DISPLAY INVISIBLE (-1575 3750);
FORCEADD OFFPAGE..2
(-1775 3850);
FORCEPROP 2 LAST $XR0 193 
J 0
(-1586 3850);
DISPLAY 0.638298 (-1586 3850);
PAINT MONO (-1586 3850);
FORCEPROP 2 LAST CDS_LIB standard
J 0
(-1775 3850);
DISPLAY INVISIBLE (-1775 3850);
FORCEPROP 1 LAST OFFPAGE TRUE
J 0
(-1450 3725);
DISPLAY 0.872340 (-1450 3725);
PAINT GREEN (-1450 3725);
DISPLAY INVISIBLE (-1450 3725);
FORCEPROP 1 LAST COMMENT_BODY TRUE
J 0
(-1820 3755);
DISPLAY 0.872340 (-1820 3755);
PAINT GREEN (-1820 3755);
DISPLAY INVISIBLE (-1820 3755);
FORCEPROP 2 LAST PATH I77
J 0
(-1575 3900);
DISPLAY 0.680851 (-1575 3900);
DISPLAY INVISIBLE (-1575 3900);
FORCEADD OFFPAGE..2
(-1775 4000);
FORCEPROP 2 LAST $XR0 210 
J 0
(-1586 4000);
DISPLAY 0.638298 (-1586 4000);
PAINT MONO (-1586 4000);
FORCEPROP 2 LAST CDS_LIB standard
J 0
(-1775 4000);
DISPLAY INVISIBLE (-1775 4000);
FORCEPROP 1 LAST OFFPAGE TRUE
J 0
(-1450 3875);
DISPLAY 0.872340 (-1450 3875);
PAINT GREEN (-1450 3875);
DISPLAY INVISIBLE (-1450 3875);
FORCEPROP 1 LAST COMMENT_BODY TRUE
J 0
(-1820 3905);
DISPLAY 0.872340 (-1820 3905);
PAINT GREEN (-1820 3905);
DISPLAY INVISIBLE (-1820 3905);
FORCEPROP 2 LAST PATH I78
J 0
(-1575 4050);
DISPLAY 0.680851 (-1575 4050);
DISPLAY INVISIBLE (-1575 4050);
FORCEADD Q_RES..1
R 2
(-2775 4100);
FORCEPROP 1 LAST LOCATION R63
J 0
(-2975 4100);
DISPLAY 0.489362 (-2975 4100);
PAINT SKYBLUE (-2975 4100);
FORCEPROP 0 LAST $SEC 1
J 0
(-2900 4150);
DISPLAY 0.680851 (-2900 4150);
PAINT MONO (-2900 4150);
DISPLAY INVISIBLE (-2900 4150);
FORCEPROP 0 LAST CDS_SEC 1
J 0
(-2900 4150);
DISPLAY 1.021277 (-2900 4150);
DISPLAY INVISIBLE (-2900 4150);
FORCEPROP 1 LASTPIN (-2675 4100) $PN 1
J 2
(-2687 4112);
DISPLAY 0.489362 (-2687 4112);
PAINT MONO (-2687 4112);
FORCEPROP 1 LASTPIN (-2875 4100) $PN 2
J 2
(-2837 4112);
DISPLAY 0.489362 (-2837 4112);
PAINT MONO (-2837 4112);
FORCEPROP 1 LAST VALUE 33
J 0
(-2650 4100);
DISPLAY 0.489362 (-2650 4100);
PAINT SKYBLUE (-2650 4100);
FORCEPROP 1 LAST PACK_TYPE 0402LF
J 0
(-2950 4025);
DISPLAY 0.489362 (-2950 4025);
PAINT SKYBLUE (-2950 4025);
DISPLAY INVISIBLE (-2950 4025);
FORCEPROP 1 LAST TOLERANCE 5%
J 2
(-2650 4075);
DISPLAY 0.489362 (-2650 4075);
PAINT SKYBLUE (-2650 4075);
DISPLAY INVISIBLE (-2650 4075);
FORCEPROP 1 LAST MATERIAL CHIP
J 0
(-2950 4075);
DISPLAY 0.489362 (-2950 4075);
PAINT SKYBLUE (-2950 4075);
DISPLAY INVISIBLE (-2950 4075);
FORCEPROP 1 LAST WATTAGE 1/16W
J 0
(-2700 4025);
DISPLAY 0.489362 (-2700 4025);
PAINT SKYBLUE (-2700 4025);
DISPLAY INVISIBLE (-2700 4025);
FORCEPROP 2 LAST CDS_LIB pure_quanta
J 0
(-2775 4100);
DISPLAY INVISIBLE (-2775 4100);
FORCEPROP 2 LAST BOM_COST MEM
J 0
(-2800 4250);
DISPLAY 0.744681 (-2800 4250);
PAINT WHITE (-2800 4250);
DISPLAY INVISIBLE (-2800 4250);
FORCEPROP 1 LAST PATH I79
J 2
(-2725 4250);
DISPLAY 0.978723 (-2725 4250);
PAINT WHITE (-2725 4250);
DISPLAY INVISIBLE (-2725 4250);
FORCEPROP 1 LAST PART_NUMBER CS03302JB10
J 0
(-2875 4150);
DISPLAY 0.489362 (-2875 4150);
PAINT SKYBLUE (-2875 4150);
DISPLAY INVISIBLE (-2875 4150);
FORCEADD OFFPAGE..2
R 2
(-7875 3300);
FORCEPROP 2 LAST $XR3 136 
J 0
(-8459 3300);
DISPLAY 0.638298 (-8459 3300);
PAINT MONO (-8459 3300);
FORCEPROP 2 LAST $XR2 135 
J 0
(-8339 3300);
DISPLAY 0.638298 (-8339 3300);
PAINT MONO (-8339 3300);
FORCEPROP 2 LAST $XR1 134 
J 0
(-8219 3300);
DISPLAY 0.638298 (-8219 3300);
PAINT MONO (-8219 3300);
FORCEPROP 2 LAST $XR0 83 
J 0
(-8099 3300);
DISPLAY 0.638298 (-8099 3300);
PAINT MONO (-8099 3300);
FORCEPROP 2 LAST CDS_LIB standard
J 0
(-7875 3300);
DISPLAY INVISIBLE (-7875 3300);
FORCEPROP 1 LAST OFFPAGE TRUE
J 2
(-8200 3175);
DISPLAY 0.872340 (-8200 3175);
PAINT GREEN (-8200 3175);
DISPLAY INVISIBLE (-8200 3175);
FORCEPROP 1 LAST COMMENT_BODY TRUE
J 2
(-7830 3205);
DISPLAY 0.872340 (-7830 3205);
PAINT GREEN (-7830 3205);
DISPLAY INVISIBLE (-7830 3205);
FORCEPROP 2 LAST PATH I8
J 0
(-8125 3350);
DISPLAY 0.680851 (-8125 3350);
DISPLAY INVISIBLE (-8125 3350);
FORCEADD Q_RES..1
R 2
(-2775 4600);
FORCEPROP 1 LAST LOCATION R211
J 0
(-2975 4600);
DISPLAY 0.489362 (-2975 4600);
PAINT SKYBLUE (-2975 4600);
FORCEPROP 0 LAST $SEC 1
J 0
(-2825 4650);
DISPLAY 0.680851 (-2825 4650);
PAINT MONO (-2825 4650);
DISPLAY INVISIBLE (-2825 4650);
FORCEPROP 0 LAST CDS_SEC 1
J 0
(-2825 4650);
DISPLAY 1.021277 (-2825 4650);
DISPLAY INVISIBLE (-2825 4650);
FORCEPROP 1 LASTPIN (-2675 4600) $PN 1
J 2
(-2687 4612);
DISPLAY 0.489362 (-2687 4612);
PAINT MONO (-2687 4612);
FORCEPROP 1 LASTPIN (-2875 4600) $PN 2
J 2
(-2860 4610);
DISPLAY 0.489362 (-2860 4610);
PAINT MONO (-2860 4610);
FORCEPROP 1 LAST VALUE 0
J 0
(-2650 4600);
DISPLAY 0.489362 (-2650 4600);
PAINT SKYBLUE (-2650 4600);
FORCEPROP 2 LAST BOM_COST MEM
J 0
(-2800 4750);
DISPLAY 0.744681 (-2800 4750);
PAINT WHITE (-2800 4750);
DISPLAY INVISIBLE (-2800 4750);
FORCEPROP 2 LAST CDS_LIB pure_quanta
J 0
(-2775 4600);
DISPLAY INVISIBLE (-2775 4600);
FORCEPROP 1 LAST WATTAGE 1/16W
J 0
(-2700 4525);
DISPLAY 0.489362 (-2700 4525);
PAINT SKYBLUE (-2700 4525);
DISPLAY INVISIBLE (-2700 4525);
FORCEPROP 1 LAST MATERIAL CHIP
J 0
(-2950 4575);
DISPLAY 0.489362 (-2950 4575);
PAINT SKYBLUE (-2950 4575);
DISPLAY INVISIBLE (-2950 4575);
FORCEPROP 1 LAST TOLERANCE 5%
J 2
(-2650 4575);
DISPLAY 0.489362 (-2650 4575);
PAINT SKYBLUE (-2650 4575);
DISPLAY INVISIBLE (-2650 4575);
FORCEPROP 1 LAST PACK_TYPE 0402LF
J 0
(-2950 4525);
DISPLAY 0.489362 (-2950 4525);
PAINT SKYBLUE (-2950 4525);
DISPLAY INVISIBLE (-2950 4525);
FORCEPROP 1 LAST PATH I80
J 2
(-2725 4750);
DISPLAY 0.978723 (-2725 4750);
PAINT WHITE (-2725 4750);
DISPLAY INVISIBLE (-2725 4750);
FORCEPROP 1 LAST PART_NUMBER CS00002JB13
J 0
(-2875 4650);
DISPLAY 0.489362 (-2875 4650);
PAINT SKYBLUE (-2875 4650);
DISPLAY INVISIBLE (-2875 4650);
FORCEADD Q_RES..1
R 2
(-2775 4650);
FORCEPROP 1 LAST LOCATION R210
J 0
(-2975 4650);
DISPLAY 0.489362 (-2975 4650);
PAINT SKYBLUE (-2975 4650);
FORCEPROP 0 LAST $SEC 1
J 0
(-2825 4700);
DISPLAY 0.680851 (-2825 4700);
PAINT MONO (-2825 4700);
DISPLAY INVISIBLE (-2825 4700);
FORCEPROP 0 LAST CDS_SEC 1
J 0
(-2825 4700);
DISPLAY 1.021277 (-2825 4700);
DISPLAY INVISIBLE (-2825 4700);
FORCEPROP 1 LASTPIN (-2675 4650) $PN 1
J 2
(-2687 4662);
DISPLAY 0.489362 (-2687 4662);
PAINT MONO (-2687 4662);
FORCEPROP 1 LASTPIN (-2875 4650) $PN 2
J 2
(-2860 4660);
DISPLAY 0.489362 (-2860 4660);
PAINT MONO (-2860 4660);
FORCEPROP 1 LAST VALUE 0
J 0
(-2650 4650);
DISPLAY 0.489362 (-2650 4650);
PAINT SKYBLUE (-2650 4650);
FORCEPROP 1 LAST PACK_TYPE 0402LF
J 0
(-2950 4575);
DISPLAY 0.489362 (-2950 4575);
PAINT SKYBLUE (-2950 4575);
DISPLAY INVISIBLE (-2950 4575);
FORCEPROP 1 LAST TOLERANCE 5%
J 2
(-2650 4625);
DISPLAY 0.489362 (-2650 4625);
PAINT SKYBLUE (-2650 4625);
DISPLAY INVISIBLE (-2650 4625);
FORCEPROP 1 LAST MATERIAL CHIP
J 0
(-2950 4625);
DISPLAY 0.489362 (-2950 4625);
PAINT SKYBLUE (-2950 4625);
DISPLAY INVISIBLE (-2950 4625);
FORCEPROP 1 LAST WATTAGE 1/16W
J 0
(-2700 4575);
DISPLAY 0.489362 (-2700 4575);
PAINT SKYBLUE (-2700 4575);
DISPLAY INVISIBLE (-2700 4575);
FORCEPROP 2 LAST CDS_LIB pure_quanta
J 0
(-2775 4650);
DISPLAY INVISIBLE (-2775 4650);
FORCEPROP 2 LAST BOM_COST MEM
J 0
(-2800 4800);
DISPLAY 0.744681 (-2800 4800);
PAINT WHITE (-2800 4800);
DISPLAY INVISIBLE (-2800 4800);
FORCEPROP 1 LAST PATH I81
J 2
(-2725 4800);
DISPLAY 0.978723 (-2725 4800);
PAINT WHITE (-2725 4800);
DISPLAY INVISIBLE (-2725 4800);
FORCEPROP 1 LAST PART_NUMBER CS00002JB13
J 0
(-2875 4700);
DISPLAY 0.489362 (-2875 4700);
PAINT SKYBLUE (-2875 4700);
DISPLAY INVISIBLE (-2875 4700);
FORCEADD Q_RES..1
R 2
(-2775 4900);
FORCEPROP 1 LAST LOCATION R56
J 0
(-2975 4900);
DISPLAY 0.489362 (-2975 4900);
PAINT SKYBLUE (-2975 4900);
FORCEPROP 0 LAST $SEC 1
J 0
(-2825 4950);
DISPLAY 0.680851 (-2825 4950);
PAINT MONO (-2825 4950);
DISPLAY INVISIBLE (-2825 4950);
FORCEPROP 0 LAST CDS_SEC 1
J 0
(-2825 4950);
DISPLAY 1.021277 (-2825 4950);
DISPLAY INVISIBLE (-2825 4950);
FORCEPROP 1 LASTPIN (-2675 4900) $PN 1
J 2
(-2687 4912);
DISPLAY 0.489362 (-2687 4912);
PAINT MONO (-2687 4912);
FORCEPROP 1 LASTPIN (-2875 4900) $PN 2
J 2
(-2860 4910);
DISPLAY 0.489362 (-2860 4910);
PAINT MONO (-2860 4910);
FORCEPROP 1 LAST VALUE 0
J 0
(-2650 4900);
DISPLAY 0.489362 (-2650 4900);
PAINT SKYBLUE (-2650 4900);
FORCEPROP 2 LAST CDS_LIB pure_quanta
J 0
(-2775 4900);
DISPLAY INVISIBLE (-2775 4900);
FORCEPROP 2 LAST BOM_COST MEM
J 0
(-2800 5050);
DISPLAY 0.744681 (-2800 5050);
PAINT WHITE (-2800 5050);
DISPLAY INVISIBLE (-2800 5050);
FORCEPROP 1 LAST WATTAGE 1/16W
J 0
(-2700 4825);
DISPLAY 0.489362 (-2700 4825);
PAINT SKYBLUE (-2700 4825);
DISPLAY INVISIBLE (-2700 4825);
FORCEPROP 1 LAST MATERIAL CHIP
J 0
(-2950 4875);
DISPLAY 0.489362 (-2950 4875);
PAINT SKYBLUE (-2950 4875);
DISPLAY INVISIBLE (-2950 4875);
FORCEPROP 1 LAST TOLERANCE 5%
J 2
(-2650 4875);
DISPLAY 0.489362 (-2650 4875);
PAINT SKYBLUE (-2650 4875);
DISPLAY INVISIBLE (-2650 4875);
FORCEPROP 1 LAST PACK_TYPE 0402LF
J 0
(-2950 4825);
DISPLAY 0.489362 (-2950 4825);
PAINT SKYBLUE (-2950 4825);
DISPLAY INVISIBLE (-2950 4825);
FORCEPROP 1 LAST PATH I82
J 2
(-2725 5050);
DISPLAY 0.978723 (-2725 5050);
PAINT WHITE (-2725 5050);
DISPLAY INVISIBLE (-2725 5050);
FORCEPROP 1 LAST PART_NUMBER CS00002JB13
J 0
(-2875 4950);
DISPLAY 0.489362 (-2875 4950);
PAINT SKYBLUE (-2875 4950);
DISPLAY INVISIBLE (-2875 4950);
FORCEADD Q_RES..1
R 2
(-2775 4950);
FORCEPROP 1 LAST LOCATION R51
J 0
(-2975 4950);
DISPLAY 0.489362 (-2975 4950);
PAINT SKYBLUE (-2975 4950);
FORCEPROP 0 LAST $SEC 1
J 0
(-2825 5000);
DISPLAY 0.680851 (-2825 5000);
PAINT MONO (-2825 5000);
DISPLAY INVISIBLE (-2825 5000);
FORCEPROP 0 LAST CDS_SEC 1
J 0
(-2825 5000);
DISPLAY 1.021277 (-2825 5000);
DISPLAY INVISIBLE (-2825 5000);
FORCEPROP 1 LASTPIN (-2675 4950) $PN 1
J 2
(-2687 4962);
DISPLAY 0.489362 (-2687 4962);
PAINT MONO (-2687 4962);
FORCEPROP 1 LASTPIN (-2875 4950) $PN 2
J 2
(-2860 4960);
DISPLAY 0.489362 (-2860 4960);
PAINT MONO (-2860 4960);
FORCEPROP 1 LAST VALUE 0
J 0
(-2650 4950);
DISPLAY 0.489362 (-2650 4950);
PAINT SKYBLUE (-2650 4950);
FORCEPROP 1 LAST PACK_TYPE 0402LF
J 0
(-2950 4875);
DISPLAY 0.489362 (-2950 4875);
PAINT SKYBLUE (-2950 4875);
DISPLAY INVISIBLE (-2950 4875);
FORCEPROP 1 LAST TOLERANCE 5%
J 2
(-2650 4925);
DISPLAY 0.489362 (-2650 4925);
PAINT SKYBLUE (-2650 4925);
DISPLAY INVISIBLE (-2650 4925);
FORCEPROP 1 LAST MATERIAL CHIP
J 0
(-2950 4925);
DISPLAY 0.489362 (-2950 4925);
PAINT SKYBLUE (-2950 4925);
DISPLAY INVISIBLE (-2950 4925);
FORCEPROP 1 LAST WATTAGE 1/16W
J 0
(-2700 4875);
DISPLAY 0.489362 (-2700 4875);
PAINT SKYBLUE (-2700 4875);
DISPLAY INVISIBLE (-2700 4875);
FORCEPROP 2 LAST BOM_COST MEM
J 0
(-2800 5100);
DISPLAY 0.744681 (-2800 5100);
PAINT WHITE (-2800 5100);
DISPLAY INVISIBLE (-2800 5100);
FORCEPROP 2 LAST CDS_LIB pure_quanta
J 0
(-2775 4950);
DISPLAY INVISIBLE (-2775 4950);
FORCEPROP 1 LAST PATH I83
J 2
(-2725 5100);
DISPLAY 0.978723 (-2725 5100);
PAINT WHITE (-2725 5100);
DISPLAY INVISIBLE (-2725 5100);
FORCEPROP 1 LAST PART_NUMBER CS00002JB13
J 0
(-2875 5000);
DISPLAY 0.489362 (-2875 5000);
PAINT SKYBLUE (-2875 5000);
DISPLAY INVISIBLE (-2875 5000);
FORCEADD OFFPAGE..2
(-1775 4100);
FORCEPROP 2 LAST $XR0 85 
J 0
(-1586 4100);
DISPLAY 0.638298 (-1586 4100);
PAINT MONO (-1586 4100);
FORCEPROP 2 LAST CDS_LIB standard
J 0
(-1775 4100);
DISPLAY INVISIBLE (-1775 4100);
FORCEPROP 1 LAST OFFPAGE TRUE
J 0
(-1450 3975);
DISPLAY 0.872340 (-1450 3975);
PAINT GREEN (-1450 3975);
DISPLAY INVISIBLE (-1450 3975);
FORCEPROP 1 LAST COMMENT_BODY TRUE
J 0
(-1820 4005);
DISPLAY 0.872340 (-1820 4005);
PAINT GREEN (-1820 4005);
DISPLAY INVISIBLE (-1820 4005);
FORCEPROP 2 LAST PATH I84
J 0
(-1575 4150);
DISPLAY 0.680851 (-1575 4150);
DISPLAY INVISIBLE (-1575 4150);
FORCEADD OFFPAGE..1
R 2
(-1775 4500);
FORCEPROP 2 LAST $XR1 151 
J 0
(-1469 4500);
DISPLAY 0.638298 (-1469 4500);
PAINT MONO (-1469 4500);
FORCEPROP 2 LAST $XR0 150 
J 0
(-1589 4500);
DISPLAY 0.638298 (-1589 4500);
PAINT MONO (-1589 4500);
FORCEPROP 2 LAST CDS_LIB standard
J 2
(-1775 4500);
DISPLAY INVISIBLE (-1775 4500);
FORCEPROP 1 LAST OFFPAGE TRUE
J 2
(-2105 4370);
PAINT GREEN (-2105 4370);
DISPLAY INVISIBLE (-2105 4370);
FORCEPROP 1 LAST COMMENT_BODY TRUE
J 2
(-1905 4400);
DISPLAY 1.106383 (-1905 4400);
PAINT PEACH (-1905 4400);
DISPLAY INVISIBLE (-1905 4400);
FORCEPROP 2 LAST PATH I85
J 0
(-1450 4550);
DISPLAY 0.680851 (-1450 4550);
DISPLAY INVISIBLE (-1450 4550);
FORCEADD OFFPAGE..1
R 2
(-1775 4550);
FORCEPROP 2 LAST $XR0 150 
J 0
(-1589 4550);
DISPLAY 0.638298 (-1589 4550);
PAINT MONO (-1589 4550);
FORCEPROP 2 LAST CDS_LIB standard
J 0
(-1775 4550);
DISPLAY INVISIBLE (-1775 4550);
FORCEPROP 1 LAST OFFPAGE TRUE
J 2
(-2105 4420);
PAINT GREEN (-2105 4420);
DISPLAY INVISIBLE (-2105 4420);
FORCEPROP 1 LAST COMMENT_BODY TRUE
J 2
(-1905 4450);
DISPLAY 1.106383 (-1905 4450);
PAINT PEACH (-1905 4450);
DISPLAY INVISIBLE (-1905 4450);
FORCEPROP 2 LAST PATH I86
J 0
(-1550 4600);
DISPLAY 0.680851 (-1550 4600);
DISPLAY INVISIBLE (-1550 4600);
FORCEADD OFFPAGE..1
R 2
(-1775 4650);
FORCEPROP 2 LAST $XR0 151 
J 0
(-1589 4650);
DISPLAY 0.638298 (-1589 4650);
PAINT MONO (-1589 4650);
FORCEPROP 2 LAST CDS_LIB standard
J 0
(-1775 4650);
DISPLAY INVISIBLE (-1775 4650);
FORCEPROP 1 LAST OFFPAGE TRUE
J 2
(-2100 4525);
DISPLAY 0.872340 (-2100 4525);
PAINT GREEN (-2100 4525);
DISPLAY INVISIBLE (-2100 4525);
FORCEPROP 1 LAST COMMENT_BODY TRUE
J 2
(-1900 4550);
DISPLAY 0.872340 (-1900 4550);
PAINT GREEN (-1900 4550);
DISPLAY INVISIBLE (-1900 4550);
FORCEPROP 2 LAST PATH I87
J 0
(-1600 4725);
DISPLAY 0.680851 (-1600 4725);
DISPLAY INVISIBLE (-1600 4725);
FORCEADD OFFPAGE..3
(-1775 4600);
FORCEPROP 2 LAST $XR0 151 
J 0
(-1561 4600);
DISPLAY 0.638298 (-1561 4600);
PAINT MONO (-1561 4600);
FORCEPROP 2 LAST CDS_LIB standard
J 0
(-1775 4600);
DISPLAY INVISIBLE (-1775 4600);
FORCEPROP 1 LAST OFFPAGE TRUE
J 0
(-1450 4475);
DISPLAY 0.872340 (-1450 4475);
PAINT GREEN (-1450 4475);
DISPLAY INVISIBLE (-1450 4475);
FORCEPROP 1 LAST COMMENT_BODY TRUE
J 0
(-1825 4500);
DISPLAY 0.872340 (-1825 4500);
PAINT GREEN (-1825 4500);
DISPLAY INVISIBLE (-1825 4500);
FORCEPROP 2 LAST PATH I88
J 0
(-1575 4675);
DISPLAY 0.680851 (-1575 4675);
DISPLAY INVISIBLE (-1575 4675);
FORCEADD OFFPAGE..2
(-1775 4700);
FORCEPROP 2 LAST $XR0 150 
J 0
(-1586 4700);
DISPLAY 0.638298 (-1586 4700);
PAINT MONO (-1586 4700);
FORCEPROP 2 LAST CDS_LIB standard
J 0
(-1775 4700);
DISPLAY INVISIBLE (-1775 4700);
FORCEPROP 1 LAST OFFPAGE TRUE
J 0
(-1450 4575);
DISPLAY 0.872340 (-1450 4575);
DISPLAY INVISIBLE (-1450 4575);
FORCEPROP 1 LAST COMMENT_BODY TRUE
J 0
(-1820 4605);
DISPLAY 0.872340 (-1820 4605);
PAINT GREEN (-1820 4605);
DISPLAY INVISIBLE (-1820 4605);
FORCEPROP 2 LAST PATH I89
J 0
(-1600 4775);
DISPLAY 0.680851 (-1600 4775);
DISPLAY INVISIBLE (-1600 4775);
FORCEADD OFFPAGE..2
R 2
(-7875 3400);
FORCEPROP 2 LAST $XR3 248 
J 0
(-8459 3400);
DISPLAY 0.638298 (-8459 3400);
PAINT MONO (-8459 3400);
FORCEPROP 2 LAST $XR2 135 
J 0
(-8339 3400);
DISPLAY 0.638298 (-8339 3400);
PAINT MONO (-8339 3400);
FORCEPROP 2 LAST $XR1 134 
J 0
(-8219 3400);
DISPLAY 0.638298 (-8219 3400);
PAINT MONO (-8219 3400);
FORCEPROP 2 LAST $XR0 83 
J 0
(-8099 3400);
DISPLAY 0.638298 (-8099 3400);
PAINT MONO (-8099 3400);
FORCEPROP 2 LAST CDS_LIB standard
J 0
(-7875 3400);
DISPLAY INVISIBLE (-7875 3400);
FORCEPROP 1 LAST OFFPAGE TRUE
J 2
(-8200 3275);
DISPLAY 0.872340 (-8200 3275);
PAINT GREEN (-8200 3275);
DISPLAY INVISIBLE (-8200 3275);
FORCEPROP 1 LAST COMMENT_BODY TRUE
J 2
(-7830 3305);
DISPLAY 0.872340 (-7830 3305);
PAINT GREEN (-7830 3305);
DISPLAY INVISIBLE (-7830 3305);
FORCEPROP 2 LAST PATH I9
J 0
(-8125 3450);
DISPLAY 0.680851 (-8125 3450);
DISPLAY INVISIBLE (-8125 3450);
FORCEADD OFFPAGE..3
(-1775 4900);
FORCEPROP 2 LAST $XR0 151 
J 0
(-1561 4900);
DISPLAY 0.638298 (-1561 4900);
PAINT MONO (-1561 4900);
FORCEPROP 2 LAST CDS_LIB standard
J 0
(-1775 4900);
DISPLAY INVISIBLE (-1775 4900);
FORCEPROP 1 LAST OFFPAGE TRUE
J 0
(-1450 4775);
DISPLAY 0.872340 (-1450 4775);
PAINT GREEN (-1450 4775);
DISPLAY INVISIBLE (-1450 4775);
FORCEPROP 1 LAST COMMENT_BODY TRUE
J 0
(-1825 4800);
DISPLAY 0.872340 (-1825 4800);
PAINT GREEN (-1825 4800);
DISPLAY INVISIBLE (-1825 4800);
FORCEPROP 2 LAST PATH I90
J 0
(-1575 4975);
DISPLAY 0.680851 (-1575 4975);
DISPLAY INVISIBLE (-1575 4975);
FORCEADD OFFPAGE..1
R 2
(-1775 4950);
FORCEPROP 2 LAST $XR0 151 
J 0
(-1589 4950);
DISPLAY 0.638298 (-1589 4950);
PAINT MONO (-1589 4950);
FORCEPROP 2 LAST CDS_LIB standard
J 0
(-1775 4950);
DISPLAY INVISIBLE (-1775 4950);
FORCEPROP 1 LAST OFFPAGE TRUE
J 2
(-2100 4825);
DISPLAY 0.872340 (-2100 4825);
PAINT GREEN (-2100 4825);
DISPLAY INVISIBLE (-2100 4825);
FORCEPROP 1 LAST COMMENT_BODY TRUE
J 2
(-1900 4850);
DISPLAY 0.872340 (-1900 4850);
PAINT GREEN (-1900 4850);
DISPLAY INVISIBLE (-1900 4850);
FORCEPROP 2 LAST PATH I91
J 0
(-1600 5025);
DISPLAY 0.680851 (-1600 5025);
DISPLAY INVISIBLE (-1600 5025);
FORCEADD OFFPAGE..1
R 2
(-1775 5000);
FORCEPROP 2 LAST $XR1 150 
J 0
(-1499 5000);
DISPLAY 0.638298 (-1499 5000);
PAINT MONO (-1499 5000);
FORCEPROP 2 LAST $XR0 83 
J 0
(-1589 5000);
DISPLAY 0.638298 (-1589 5000);
PAINT MONO (-1589 5000);
FORCEPROP 2 LAST CDS_LIB standard
J 0
(-1775 5000);
DISPLAY INVISIBLE (-1775 5000);
FORCEPROP 1 LAST OFFPAGE TRUE
J 2
(-2105 4870);
PAINT GREEN (-2105 4870);
DISPLAY INVISIBLE (-2105 4870);
FORCEPROP 1 LAST COMMENT_BODY TRUE
J 2
(-1905 4900);
DISPLAY 1.106383 (-1905 4900);
PAINT PEACH (-1905 4900);
DISPLAY INVISIBLE (-1905 4900);
FORCEPROP 2 LAST PATH I92
J 0
(-1475 5050);
DISPLAY 0.680851 (-1475 5050);
DISPLAY INVISIBLE (-1475 5050);
FORCEADD LCMXO3LF9400C5BG484C..3
(-4825 3850);
FORCEPROP 1 LAST LOCATION U18
J 0
(-5725 5300);
DISPLAY 0.723404 (-5725 5300);
PAINT GREEN (-5725 5300);
FORCEPROP 0 LAST $SEC 3
J 0
(-5725 5450);
DISPLAY 0.680851 (-5725 5450);
PAINT MONO (-5725 5450);
DISPLAY INVISIBLE (-5725 5450);
FORCEPROP 0 LAST CDS_SEC 3
J 0
(-5725 5525);
DISPLAY 0.680851 (-5725 5525);
DISPLAY INVISIBLE (-5725 5525);
FORCEPROP 0 LASTPIN (-5875 5000) $PN B1
J 2
(-5885 5010);
DISPLAY 0.680851 (-5885 5010);
PAINT MONO (-5885 5010);
FORCEPROP 0 LASTPIN (-5875 4950) $PN A2
J 2
(-5885 4960);
DISPLAY 0.680851 (-5885 4960);
PAINT MONO (-5885 4960);
FORCEPROP 0 LASTPIN (-5875 4900) $PN E6
J 2
(-5885 4910);
DISPLAY 0.680851 (-5885 4910);
PAINT MONO (-5885 4910);
FORCEPROP 0 LASTPIN (-5875 4850) $PN F7
J 2
(-5885 4860);
DISPLAY 0.680851 (-5885 4860);
PAINT MONO (-5885 4860);
FORCEPROP 0 LASTPIN (-5875 4800) $PN B2
J 2
(-5885 4810);
DISPLAY 0.680851 (-5885 4810);
PAINT MONO (-5885 4810);
FORCEPROP 0 LASTPIN (-5875 4750) $PN A3
J 2
(-5885 4760);
DISPLAY 0.680851 (-5885 4760);
PAINT MONO (-5885 4760);
FORCEPROP 0 LASTPIN (-5875 4700) $PN C3
J 2
(-5885 4710);
DISPLAY 0.680851 (-5885 4710);
PAINT MONO (-5885 4710);
FORCEPROP 0 LASTPIN (-5875 4650) $PN C4
J 2
(-5885 4660);
DISPLAY 0.680851 (-5885 4660);
PAINT MONO (-5885 4660);
FORCEPROP 0 LASTPIN (-5875 4600) $PN B3
J 2
(-5885 4610);
DISPLAY 0.680851 (-5885 4610);
PAINT MONO (-5885 4610);
FORCEPROP 0 LASTPIN (-5875 4550) $PN A4
J 2
(-5885 4560);
DISPLAY 0.680851 (-5885 4560);
PAINT MONO (-5885 4560);
FORCEPROP 0 LASTPIN (-5875 4500) $PN F8
J 2
(-5885 4510);
DISPLAY 0.680851 (-5885 4510);
PAINT MONO (-5885 4510);
FORCEPROP 0 LASTPIN (-5875 4450) $PN G8
J 2
(-5885 4460);
DISPLAY 0.680851 (-5885 4460);
PAINT MONO (-5885 4460);
FORCEPROP 0 LASTPIN (-5875 4400) $PN B4
J 2
(-5885 4410);
DISPLAY 0.680851 (-5885 4410);
PAINT MONO (-5885 4410);
FORCEPROP 0 LASTPIN (-5875 4350) $PN A5
J 2
(-5885 4360);
DISPLAY 0.680851 (-5885 4360);
PAINT MONO (-5885 4360);
FORCEPROP 0 LASTPIN (-5875 4300) $PN D5
J 2
(-5885 4310);
DISPLAY 0.680851 (-5885 4310);
PAINT MONO (-5885 4310);
FORCEPROP 0 LASTPIN (-5875 4250) $PN C5
J 2
(-5885 4260);
DISPLAY 0.680851 (-5885 4260);
PAINT MONO (-5885 4260);
FORCEPROP 0 LASTPIN (-5875 4200) $PN B5
J 2
(-5885 4210);
DISPLAY 0.680851 (-5885 4210);
PAINT MONO (-5885 4210);
FORCEPROP 0 LASTPIN (-5875 4150) $PN A6
J 2
(-5885 4160);
DISPLAY 0.680851 (-5885 4160);
PAINT MONO (-5885 4160);
FORCEPROP 0 LASTPIN (-5875 4100) $PN D6
J 2
(-5885 4110);
DISPLAY 0.680851 (-5885 4110);
PAINT MONO (-5885 4110);
FORCEPROP 0 LASTPIN (-5875 4050) $PN E7
J 2
(-5885 4060);
DISPLAY 0.680851 (-5885 4060);
PAINT MONO (-5885 4060);
FORCEPROP 0 LASTPIN (-5875 4000) $PN B6
J 2
(-5885 4010);
DISPLAY 0.680851 (-5885 4010);
PAINT MONO (-5885 4010);
FORCEPROP 0 LASTPIN (-5875 3950) $PN A7
J 2
(-5885 3960);
DISPLAY 0.680851 (-5885 3960);
PAINT MONO (-5885 3960);
FORCEPROP 0 LASTPIN (-5875 3900) $PN C6
J 2
(-5885 3910);
DISPLAY 0.680851 (-5885 3910);
PAINT MONO (-5885 3910);
FORCEPROP 0 LASTPIN (-5875 3850) $PN D7
J 2
(-5885 3860);
DISPLAY 0.680851 (-5885 3860);
PAINT MONO (-5885 3860);
FORCEPROP 0 LASTPIN (-5875 3800) $PN C8
J 2
(-5885 3810);
DISPLAY 0.680851 (-5885 3810);
PAINT MONO (-5885 3810);
FORCEPROP 0 LASTPIN (-5875 3750) $PN D8
J 2
(-5885 3760);
DISPLAY 0.680851 (-5885 3760);
PAINT MONO (-5885 3760);
FORCEPROP 0 LASTPIN (-5875 3700) $PN B8
J 2
(-5885 3710);
DISPLAY 0.680851 (-5885 3710);
PAINT MONO (-5885 3710);
FORCEPROP 0 LASTPIN (-5875 3650) $PN A8
J 2
(-5885 3660);
DISPLAY 0.680851 (-5885 3660);
PAINT MONO (-5885 3660);
FORCEPROP 0 LASTPIN (-5875 3600) $PN C9
J 2
(-5885 3610);
DISPLAY 0.680851 (-5885 3610);
PAINT MONO (-5885 3610);
FORCEPROP 0 LASTPIN (-5875 3550) $PN D9
J 2
(-5885 3560);
DISPLAY 0.680851 (-5885 3560);
PAINT MONO (-5885 3560);
FORCEPROP 0 LASTPIN (-5875 3400) $PN B9
J 2
(-5885 3410);
DISPLAY 0.680851 (-5885 3410);
PAINT MONO (-5885 3410);
FORCEPROP 0 LASTPIN (-5875 3350) $PN A9
J 2
(-5885 3360);
DISPLAY 0.680851 (-5885 3360);
PAINT MONO (-5885 3360);
FORCEPROP 0 LASTPIN (-5875 3300) $PN F9
J 2
(-5885 3310);
DISPLAY 0.680851 (-5885 3310);
PAINT MONO (-5885 3310);
FORCEPROP 0 LASTPIN (-5875 3250) $PN G9
J 2
(-5885 3260);
DISPLAY 0.680851 (-5885 3260);
PAINT MONO (-5885 3260);
FORCEPROP 0 LASTPIN (-5875 3200) $PN F10
J 2
(-5885 3210);
DISPLAY 0.680851 (-5885 3210);
PAINT MONO (-5885 3210);
FORCEPROP 0 LASTPIN (-5875 3150) $PN E10
J 2
(-5885 3160);
DISPLAY 0.680851 (-5885 3160);
PAINT MONO (-5885 3160);
FORCEPROP 0 LASTPIN (-5875 3100) $PN B10
J 2
(-5885 3110);
DISPLAY 0.680851 (-5885 3110);
PAINT MONO (-5885 3110);
FORCEPROP 0 LASTPIN (-5875 3050) $PN A10
J 2
(-5885 3060);
DISPLAY 0.680851 (-5885 3060);
PAINT MONO (-5885 3060);
FORCEPROP 0 LASTPIN (-5875 3000) $PN G11
J 2
(-5885 3010);
DISPLAY 0.680851 (-5885 3010);
PAINT MONO (-5885 3010);
FORCEPROP 0 LASTPIN (-5875 2950) $PN F11
J 2
(-5885 2960);
DISPLAY 0.680851 (-5885 2960);
PAINT MONO (-5885 2960);
FORCEPROP 0 LASTPIN (-5875 2850) $PN B11
J 2
(-5885 2860);
DISPLAY 0.680851 (-5885 2860);
PAINT MONO (-5885 2860);
FORCEPROP 0 LASTPIN (-5875 2800) $PN A11
J 2
(-5885 2810);
DISPLAY 0.680851 (-5885 2810);
PAINT MONO (-5885 2810);
FORCEPROP 0 LASTPIN (-5875 2750) $PN E11
J 2
(-5885 2760);
DISPLAY 0.680851 (-5885 2760);
PAINT MONO (-5885 2760);
FORCEPROP 0 LASTPIN (-5875 2700) $PN D11
J 2
(-5885 2710);
DISPLAY 0.680851 (-5885 2710);
PAINT MONO (-5885 2710);
FORCEPROP 0 LASTPIN (-3775 5050) $PN D12
J 0
(-3765 5060);
DISPLAY 0.680851 (-3765 5060);
PAINT MONO (-3765 5060);
FORCEPROP 0 LASTPIN (-3775 5000) $PN E12
J 0
(-3765 5010);
DISPLAY 0.680851 (-3765 5010);
PAINT MONO (-3765 5010);
FORCEPROP 0 LASTPIN (-3775 4950) $PN B12
J 0
(-3765 4960);
DISPLAY 0.680851 (-3765 4960);
PAINT MONO (-3765 4960);
FORCEPROP 0 LASTPIN (-3775 4900) $PN A12
J 0
(-3765 4910);
DISPLAY 0.680851 (-3765 4910);
PAINT MONO (-3765 4910);
FORCEPROP 0 LASTPIN (-3775 4850) $PN G12
J 0
(-3765 4860);
DISPLAY 0.680851 (-3765 4860);
PAINT MONO (-3765 4860);
FORCEPROP 0 LASTPIN (-3775 4800) $PN F12
J 0
(-3765 4810);
DISPLAY 0.680851 (-3765 4810);
PAINT MONO (-3765 4810);
FORCEPROP 0 LASTPIN (-3775 4750) $PN E13
J 0
(-3765 4760);
DISPLAY 0.680851 (-3765 4760);
PAINT MONO (-3765 4760);
FORCEPROP 0 LASTPIN (-3775 4700) $PN F13
J 0
(-3765 4710);
DISPLAY 0.680851 (-3765 4710);
PAINT MONO (-3765 4710);
FORCEPROP 0 LASTPIN (-3775 4650) $PN A13
J 0
(-3765 4660);
DISPLAY 0.680851 (-3765 4660);
PAINT MONO (-3765 4660);
FORCEPROP 0 LASTPIN (-3775 4600) $PN B13
J 0
(-3765 4610);
DISPLAY 0.680851 (-3765 4610);
PAINT MONO (-3765 4610);
FORCEPROP 0 LASTPIN (-3775 4550) $PN C13
J 0
(-3765 4560);
DISPLAY 0.680851 (-3765 4560);
PAINT MONO (-3765 4560);
FORCEPROP 0 LASTPIN (-3775 4500) $PN D13
J 0
(-3765 4510);
DISPLAY 0.680851 (-3765 4510);
PAINT MONO (-3765 4510);
FORCEPROP 0 LASTPIN (-3775 4450) $PN A14
J 0
(-3765 4460);
DISPLAY 0.680851 (-3765 4460);
PAINT MONO (-3765 4460);
FORCEPROP 0 LASTPIN (-3775 4400) $PN B14
J 0
(-3765 4410);
DISPLAY 0.680851 (-3765 4410);
PAINT MONO (-3765 4410);
FORCEPROP 0 LASTPIN (-3775 4350) $PN C14
J 0
(-3765 4360);
DISPLAY 0.680851 (-3765 4360);
PAINT MONO (-3765 4360);
FORCEPROP 0 LASTPIN (-3775 4300) $PN D14
J 0
(-3765 4310);
DISPLAY 0.680851 (-3765 4310);
PAINT MONO (-3765 4310);
FORCEPROP 0 LASTPIN (-3775 4250) $PN G14
J 0
(-3765 4260);
DISPLAY 0.680851 (-3765 4260);
PAINT MONO (-3765 4260);
FORCEPROP 0 LASTPIN (-3775 4200) $PN F14
J 0
(-3765 4210);
DISPLAY 0.680851 (-3765 4210);
PAINT MONO (-3765 4210);
FORCEPROP 0 LASTPIN (-3775 4100) $PN A15
J 0
(-3765 4110);
DISPLAY 0.680851 (-3765 4110);
PAINT MONO (-3765 4110);
FORCEPROP 0 LASTPIN (-3775 4050) $PN B15
J 0
(-3765 4060);
DISPLAY 0.680851 (-3765 4060);
PAINT MONO (-3765 4060);
FORCEPROP 0 LASTPIN (-3775 4000) $PN C15
J 0
(-3765 4010);
DISPLAY 0.680851 (-3765 4010);
PAINT MONO (-3765 4010);
FORCEPROP 0 LASTPIN (-3775 3950) $PN D15
J 0
(-3765 3960);
DISPLAY 0.680851 (-3765 3960);
PAINT MONO (-3765 3960);
FORCEPROP 0 LASTPIN (-3775 3900) $PN A16
J 0
(-3765 3910);
DISPLAY 0.680851 (-3765 3910);
PAINT MONO (-3765 3910);
FORCEPROP 0 LASTPIN (-3775 3850) $PN B17
J 0
(-3765 3860);
DISPLAY 0.680851 (-3765 3860);
PAINT MONO (-3765 3860);
FORCEPROP 0 LASTPIN (-3775 3800) $PN C17
J 0
(-3765 3810);
DISPLAY 0.680851 (-3765 3810);
PAINT MONO (-3765 3810);
FORCEPROP 0 LASTPIN (-3775 3750) $PN D16
J 0
(-3765 3760);
DISPLAY 0.680851 (-3765 3760);
PAINT MONO (-3765 3760);
FORCEPROP 0 LASTPIN (-3775 3700) $PN A17
J 0
(-3765 3710);
DISPLAY 0.680851 (-3765 3710);
PAINT MONO (-3765 3710);
FORCEPROP 0 LASTPIN (-3775 3650) $PN B18
J 0
(-3765 3660);
DISPLAY 0.680851 (-3765 3660);
PAINT MONO (-3765 3660);
FORCEPROP 0 LASTPIN (-3775 3600) $PN E16
J 0
(-3765 3610);
DISPLAY 0.680851 (-3765 3610);
PAINT MONO (-3765 3610);
FORCEPROP 0 LASTPIN (-3775 3550) $PN D17
J 0
(-3765 3560);
DISPLAY 0.680851 (-3765 3560);
PAINT MONO (-3765 3560);
FORCEPROP 0 LASTPIN (-3775 3500) $PN A18
J 0
(-3765 3510);
DISPLAY 0.680851 (-3765 3510);
PAINT MONO (-3765 3510);
FORCEPROP 0 LASTPIN (-3775 3450) $PN B19
J 0
(-3765 3460);
DISPLAY 0.680851 (-3765 3460);
PAINT MONO (-3765 3460);
FORCEPROP 0 LASTPIN (-3775 3400) $PN C18
J 0
(-3765 3410);
DISPLAY 0.680851 (-3765 3410);
PAINT MONO (-3765 3410);
FORCEPROP 0 LASTPIN (-3775 3350) $PN D18
J 0
(-3765 3360);
DISPLAY 0.680851 (-3765 3360);
PAINT MONO (-3765 3360);
FORCEPROP 0 LASTPIN (-3775 3250) $PN A19
J 0
(-3765 3260);
DISPLAY 0.680851 (-3765 3260);
PAINT MONO (-3765 3260);
FORCEPROP 0 LASTPIN (-3775 3200) $PN B20
J 0
(-3765 3210);
DISPLAY 0.680851 (-3765 3210);
PAINT MONO (-3765 3210);
FORCEPROP 0 LASTPIN (-3775 3150) $PN F15
J 0
(-3765 3160);
DISPLAY 0.680851 (-3765 3160);
PAINT MONO (-3765 3160);
FORCEPROP 0 LASTPIN (-3775 3100) $PN G15
J 0
(-3765 3110);
DISPLAY 0.680851 (-3765 3110);
PAINT MONO (-3765 3110);
FORCEPROP 0 LASTPIN (-3775 3000) $PN A20
J 0
(-3765 3010);
DISPLAY 0.680851 (-3765 3010);
PAINT MONO (-3765 3010);
FORCEPROP 0 LASTPIN (-3775 2950) $PN B21
J 0
(-3765 2960);
DISPLAY 0.680851 (-3765 2960);
PAINT MONO (-3765 2960);
FORCEPROP 0 LASTPIN (-3775 2900) $PN C19
J 0
(-3765 2910);
DISPLAY 0.680851 (-3765 2910);
PAINT MONO (-3765 2910);
FORCEPROP 0 LASTPIN (-3775 2850) $PN C20
J 0
(-3765 2860);
DISPLAY 0.680851 (-3765 2860);
PAINT MONO (-3765 2860);
FORCEPROP 0 LASTPIN (-3775 2750) $PN A21
J 0
(-3765 2760);
DISPLAY 0.680851 (-3765 2760);
PAINT MONO (-3765 2760);
FORCEPROP 0 LASTPIN (-3775 2700) $PN B22
J 0
(-3765 2710);
DISPLAY 0.680851 (-3765 2710);
PAINT MONO (-3765 2710);
FORCEPROP 2 LAST PART_TYPE SMLF
J 0
(-5725 5400);
DISPLAY 0.680851 (-5725 5400);
FORCEPROP 2 LAST VALUE LCMXO3LF-9400C-5BG484C
J 0
(-5725 5350);
DISPLAY 0.489362 (-5725 5350);
PAINT SKYBLUE (-5725 5350);
FORCEPROP 1 LAST MATERIAL IC
J 0
(-5718 5119);
DISPLAY 0.723404 (-5718 5119);
PAINT GREEN (-5718 5119);
FORCEPROP 1 LAST CDS_LMAN_SYM_OUTLINE -900,1250,900,-1250
J 0
(-4825 3850);
DISPLAY 0.468085 (-4825 3850);
PAINT GREEN (-4825 3850);
DISPLAY INVISIBLE (-4825 3850);
FORCEPROP 1 LAST NEEDS_NO_SIZE TRUE
J 0
(-4825 3850);
DISPLAY 0.723404 (-4825 3850);
PAINT GREEN (-4825 3850);
DISPLAY INVISIBLE (-4825 3850);
FORCEPROP 2 LAST CDS_LIB pure_quanta
J 0
(-4825 3850);
DISPLAY INVISIBLE (-4825 3850);
FORCEPROP 1 LAST PATH I94
J 0
(-4825 3850);
DISPLAY 0.723404 (-4825 3850);
PAINT GREEN (-4825 3850);
DISPLAY INVISIBLE (-4825 3850);
FORCEPROP 1 LAST PART_NUMBER AJ094000T08
J 0
(-5725 5246);
DISPLAY 0.723404 (-5725 5246);
PAINT GREEN (-5725 5246);
DISPLAY INVISIBLE (-5725 5246);
FORCEADD OFFPAGE..2
(-1775 5050);
FORCEPROP 2 LAST $XR0 241 
J 0
(-1586 5050);
DISPLAY 0.638298 (-1586 5050);
PAINT MONO (-1586 5050);
FORCEPROP 2 LAST CDS_LIB standard
J 0
(-1775 5050);
DISPLAY INVISIBLE (-1775 5050);
FORCEPROP 1 LAST OFFPAGE TRUE
J 0
(-1450 4925);
DISPLAY 0.872340 (-1450 4925);
PAINT GREEN (-1450 4925);
DISPLAY INVISIBLE (-1450 4925);
FORCEPROP 1 LAST COMMENT_BODY TRUE
J 0
(-1820 4955);
DISPLAY 0.872340 (-1820 4955);
PAINT GREEN (-1820 4955);
DISPLAY INVISIBLE (-1820 4955);
FORCEPROP 2 LAST PATH I95
J 0
(-1575 5100);
DISPLAY 0.680851 (-1575 5100);
DISPLAY INVISIBLE (-1575 5100);
FORCEADD OFFPAGE..4
R 2
(-7875 3600);
FORCEPROP 2 LAST $XR0 131 
J 0
(-8127 3600);
DISPLAY 0.638298 (-8127 3600);
PAINT MONO (-8127 3600);
FORCEPROP 2 LAST CDS_LIB standard
J 0
(-7875 3600);
DISPLAY INVISIBLE (-7875 3600);
FORCEPROP 1 LAST OFFPAGE TRUE
J 2
(-8200 3475);
DISPLAY 0.872340 (-8200 3475);
PAINT GREEN (-8200 3475);
DISPLAY INVISIBLE (-8200 3475);
FORCEPROP 1 LAST COMMENT_BODY TRUE
J 2
(-7850 3500);
DISPLAY 0.872340 (-7850 3500);
PAINT GREEN (-7850 3500);
DISPLAY INVISIBLE (-7850 3500);
FORCEPROP 2 LAST PATH I99
J 0
(-8125 3650);
DISPLAY 0.680851 (-8125 3650);
DISPLAY INVISIBLE (-8125 3650);
FORCEADD DNS..2
(-8475 4325);
PAINT RED (-8475 4325);
FORCEPROP 2 LAST CDS_LIB mstr_misc
J 0
(-8475 4325);
DISPLAY INVISIBLE (-8475 4325);
FORCEPROP 1 LAST COMMENT_BODY TRUE
R 1
J 0
(-8400 4100);
DISPLAY 0.872340 (-8400 4100);
PAINT GREEN (-8400 4100);
DISPLAY INVISIBLE (-8400 4100);
FORCEADD QUANTA_TITLE_BLOCK_C..1
(0 0);
FORCEPROP 0 LAST CDS_CON_LAST_MODIFIED Thu Sep 14 16:12:38 2023
J 0
(-1885 15);
DISPLAY INVISIBLE (-1885 15);
FORCEPROP 1 LAST CUSTOM_TXT_CDS <CON_LAST_MODIFIED>
J 0
(-1885 15);
DISPLAY 0.978723 (-1885 15);
FORCEPROP 2 LAST CUSTOM_TXT_CDS <XR_PAGE_TITLE>
J 0
(-7890 5250);
DISPLAY 0.638298 (-7890 5250);
PAINT PINK (-7890 5250);
DISPLAY INVISIBLE (-7890 5250);
FORCEPROP 1 LAST CUSTOM_TXT_CDS <NAME_2>
J 0
(-3175 50);
FORCEPROP 1 LAST CUSTOM_TXT_CDS <NAME_1>
J 0
(-3175 175);
FORCEPROP 1 LAST CUSTOM_TXT_CDS <Q_NUMBER>
J 0
(-1403 103);
DISPLAY 1.212766 (-1403 103);
FORCEPROP 1 LAST CUSTOM_TXT_CDS <Q_PROJ>
J 0
(-2382 102);
DISPLAY 1.212766 (-2382 102);
FORCEPROP 1 LAST CUSTOM_TXT_CDS <Q_REV>
J 0
(-184 103);
DISPLAY 1.212766 (-184 103);
FORCEPROP 1 LAST CUSTOM_TXT_CDS <CON_PAGE_NUM> OF <CON_TOTAL_PAGES>
J 0
(-446 18);
DISPLAY 0.978723 (-446 18);
FORCEPROP 1 LAST Q_TITLE FPGA 1/6
J 0
(-9300 50);
DISPLAY 2.446809 (-9300 50);
PAINT GREEN (-9300 50);
FORCEPROP 1 LAST CDS_LMAN_SYM_OUTLINE -9475,6775,100,-125
J 0
(0 0);
DISPLAY 0.468085 (0 0);
PAINT GREEN (0 0);
DISPLAY INVISIBLE (0 0);
FORCEPROP 2 LAST CDS_LIB pure_quanta
J 0
(0 0);
DISPLAY INVISIBLE (0 0);
FORCEPROP 2 LAST PAGE_BORDER TRUE
J 0
(-7890 5250);
DISPLAY 0.638298 (-7890 5250);
PAINT PINK (-7890 5250);
DISPLAY INVISIBLE (-7890 5250);
FORCEPROP 2 LAST CDS_XR_PAGE_TITLE CR-80 : @T6G_MB_LIB.T6G(SCH_1):PAGE80
J 0
(-7890 5250);
DISPLAY 0.638298 (-7890 5250);
PAINT PINK (-7890 5250);
DISPLAY INVISIBLE (-7890 5250);
FORCEPROP 1 LAST Q_DEPT BU9
J 1
(-3763 49);
DISPLAY 1.957447 (-3763 49);
PAINT GREEN (-3763 49);
DISPLAY INVISIBLE (-3763 49);
FORCEPROP 1 LAST COMMENT_BODY TRUE
J 0
(12 -13);
DISPLAY 0.978723 (12 -13);
PAINT GREEN (12 -13);
DISPLAY INVISIBLE (12 -13);
WIRE 16 -1 (-7825 3000)(-6950 3000);
FORCEPROP 2 LAST SIG_NAME SMB_CPU0_4_XLTR_SCL
J 0
(-7700 3010);
DISPLAY 0.489362 (-7700 3010);
WIRE 16 -1 (-2575 3400)(-1800 3400);
FORCEPROP 2 LAST SIG_NAME FM_OCP_V3_2_AUX_PWR_R_EN
J 0
(-2460 3410);
DISPLAY 0.553191 (-2460 3410);
WIRE 16 -1 (-3775 3550)(-1825 3550);
FORCEPROP 2 LAST SIG_NAME RST_SMB_SWITCH_N
J 0
(-2560 3560);
DISPLAY 0.510638 (-2560 3560);
PAINT WHITE (-2560 3560);
WIRE 16 -1 (-3775 2950)(-1825 2950);
FORCEPROP 2 LAST SIG_NAME IRQ_SML1_PMBUS_ALERT_N
J 0
(-2560 2960);
DISPLAY 0.489362 (-2560 2960);
WIRE 16 -1 (-3775 3000)(-2875 3000);
FORCEPROP 2 LAST SIG_NAME P1V8_RETIMER_CPU1_R_EN
J 0
(-3650 3010);
DISPLAY 0.489362 (-3650 3010);
FORCEPROP 2 LASTPROP $XRERR UNIQUE?
J 0
(-3890 3010);
DISPLAY 0.638298 (-3890 3010);
PAINT MONO (-3890 3010);
DISPLAY INVISIBLE (-3890 3010);
WIRE 16 -1 (-3775 3100)(-1825 3100);
FORCEPROP 2 LAST SIG_NAME FM_UARTSW_LSB_N
J 0
(-2560 3110);
DISPLAY 0.510638 (-2560 3110);
PAINT WHITE (-2560 3110);
WIRE 16 -1 (-3775 3150)(-1850 3150);
FORCEPROP 2 LAST SIG_NAME OCP_V3_2_P3V3_PLD_R_PWRGD
J 0
(-3650 3160);
DISPLAY 0.489362 (-3650 3160);
WIRE 16 -1 (-3775 3200)(-1825 3200);
FORCEPROP 2 LAST SIG_NAME FM_SOL_UART_CH_SEL
J 0
(-2560 3210);
DISPLAY 0.510638 (-2560 3210);
PAINT WHITE (-2560 3210);
WIRE 16 -1 (-1825 3250)(-3775 3250);
FORCEPROP 2 LAST SIG_NAME FM_LED_PWRGD_PVDD18_S5_P1
J 0
(-2560 3260);
DISPLAY 0.489362 (-2560 3260);
WIRE 16 -1 (-3775 3350)(-1825 3350);
FORCEPROP 2 LAST SIG_NAME SGPIO_SCM_CLK_<1>
J 0
(-2560 3360);
DISPLAY 0.510638 (-2560 3360);
PAINT WHITE (-2560 3360);
WIRE 16 -1 (-3775 3400)(-2775 3400);
FORCEPROP 2 LAST SIG_NAME FM_OCP_V3_2_AUX_PWR_EN
J 0
(-3460 3410);
DISPLAY 0.510638 (-3460 3410);
PAINT WHITE (-3460 3410);
FORCEPROP 2 LASTPROP $XRERR UNIQUE?
J 0
(-3700 3410);
DISPLAY 0.638298 (-3700 3410);
PAINT MONO (-3700 3410);
DISPLAY INVISIBLE (-3700 3410);
WIRE 16 -1 (-3775 2850)(-2875 2850);
FORCEPROP 2 LAST SIG_NAME CLK_GEN2_GPU_FPGA_OE_R_N
J 0
(-3650 2860);
DISPLAY 0.510638 (-3650 2860);
PAINT WHITE (-3650 2860);
FORCEPROP 2 LASTPROP $XRERR UNIQUE?
J 0
(-3890 2860);
DISPLAY 0.638298 (-3890 2860);
PAINT MONO (-3890 2860);
DISPLAY INVISIBLE (-3890 2860);
WIRE 16 -1 (-1825 3700)(-3775 3700);
FORCEPROP 2 LAST SIG_NAME PWRGD_PVDDCR_SOC_P1
J 0
(-2560 3710);
DISPLAY 0.489362 (-2560 3710);
WIRE 16 -1 (-1825 3450)(-3775 3450);
FORCEPROP 2 LAST SIG_NAME FM_LED_PWRGD_PVDD11_S3_P1
J 0
(-2560 3460);
DISPLAY 0.489362 (-2560 3460);
WIRE 16 -1 (-1825 3500)(-3775 3500);
FORCEPROP 2 LAST SIG_NAME FM_LED_PWRGD_PVDDIO_P1
J 0
(-2560 3510);
DISPLAY 0.489362 (-2560 3510);
WIRE 16 -1 (-2675 3800)(-1825 3800);
FORCEPROP 0 LAST SIG_NAME RST_SRST_PLD_BMC_N
J 0
(-2560 3810);
DISPLAY 0.446809 (-2560 3810);
PAINT WHITE (-2560 3810);
WIRE 16 -1 (-3775 3750)(-1825 3750);
FORCEPROP 0 LAST SIG_NAME FPGA_IO3V3_RSVD_1
J 0
(-2560 3760);
DISPLAY 0.446809 (-2560 3760);
PAINT WHITE (-2560 3760);
WIRE 16 -1 (-1825 3600)(-3775 3600);
FORCEPROP 2 LAST SIG_NAME FM_LED_PWRGD_PVDDCR_CPU1_P1
J 0
(-2560 3610);
DISPLAY 0.489362 (-2560 3610);
WIRE 16 -1 (-3775 3900)(-2875 3900);
FORCEPROP 0 LAST SIG_NAME PWRGD_P5V
J 0
(-3650 3910);
DISPLAY 0.489362 (-3650 3910);
FORCEPROP 2 LASTPROP $XRERR UNIQUE?
J 0
(-3890 3910);
DISPLAY 0.638298 (-3890 3910);
PAINT MONO (-3890 3910);
DISPLAY INVISIBLE (-3890 3910);
WIRE 16 -1 (-1825 3650)(-3775 3650);
FORCEPROP 2 LAST SIG_NAME FM_LED_PWRGD_PVDDCR_SOC_P1
J 0
(-2560 3660);
DISPLAY 0.489362 (-2560 3660);
WIRE 16 -1 (-2675 2900)(-1825 2900);
FORCEPROP 2 LAST SIG_NAME CLK_GEN2_BMC_RC_OE_N
J 0
(-2560 2910);
DISPLAY 0.510638 (-2560 2910);
PAINT WHITE (-2560 2910);
WIRE 16 -1 (-2675 3000)(-1825 3000);
FORCEPROP 2 LAST SIG_NAME P1V8_RETIMER_CPU1_EN
J 0
(-2560 3010);
DISPLAY 0.553191 (-2560 3010);
WIRE 16 -1 (-2675 4050)(-1825 4050);
FORCEPROP 2 LAST SIG_NAME P1V8_RETIMER_CPU0_EN
J 0
(-2560 4060);
DISPLAY 0.553191 (-2560 4060);
WIRE 16 -1 (-2875 4950)(-3775 4950);
FORCEPROP 0 LAST SIG_NAME SMB_1_PLD_3V3AUX_SCL_R2
J 0
(-3650 4950);
DISPLAY 0.553191 (-3650 4950);
PAINT WHITE (-3650 4950);
FORCEPROP 2 LASTPROP $XRERR UNIQUE?
J 0
(-3890 4950);
DISPLAY 0.638298 (-3890 4950);
PAINT MONO (-3890 4950);
DISPLAY INVISIBLE (-3890 4950);
WIRE 16 -1 (-2675 4650)(-1825 4650);
FORCEPROP 0 LAST SIG_NAME SMB_2_PLD_3V3AUX_SCL_R1
J 0
(-2560 4660);
DISPLAY 0.553191 (-2560 4660);
PAINT WHITE (-2560 4660);
WIRE 16 -1 (-2675 4600)(-1825 4600);
FORCEPROP 0 LAST SIG_NAME SMB_2_PLD_3V3AUX_SDA_R1
J 0
(-2560 4610);
DISPLAY 0.553191 (-2560 4610);
PAINT WHITE (-2560 4610);
WIRE 16 -1 (-2675 4100)(-1825 4100);
FORCEPROP 2 LAST SIG_NAME SCM_SYS_PWROK_R
J 0
(-2560 4110);
DISPLAY 0.489362 (-2560 4110);
WIRE 16 -1 (-3775 4050)(-2875 4050);
FORCEPROP 2 LAST SIG_NAME P1V8_RETIMER_CPU0_R_EN
J 0
(-3650 4060);
DISPLAY 0.489362 (-3650 4060);
FORCEPROP 2 LASTPROP $XRERR UNIQUE?
J 0
(-3890 4060);
DISPLAY 0.638298 (-3890 4060);
PAINT MONO (-3890 4060);
DISPLAY INVISIBLE (-3890 4060);
WIRE 16 -1 (-3775 4200)(-1825 4200);
FORCEPROP 2 LAST SIG_NAME SCM_SPARE_1
J 0
(-2560 4210);
DISPLAY 0.510638 (-2560 4210);
PAINT WHITE (-2560 4210);
WIRE 16 -1 (-1825 4550)(-3775 4550);
FORCEPROP 2 LAST SIG_NAME SCM_ROT_CPU_RST_R_N
J 0
(-2560 4560);
DISPLAY 0.489362 (-2560 4560);
WIRE 16 -1 (-1825 4500)(-3775 4500);
FORCEPROP 2 LAST SIG_NAME RST_MB_STBY_N
J 0
(-2560 4510);
DISPLAY 0.510638 (-2560 4510);
PAINT WHITE (-2560 4510);
WIRE 16 -1 (-3775 4450)(-1825 4450);
FORCEPROP 2 LAST SIG_NAME SGPIO_OCP_V3_2_LD_N
J 0
(-2560 4460);
DISPLAY 0.510638 (-2560 4460);
PAINT WHITE (-2560 4460);
WIRE 16 -1 (-3775 4400)(-1825 4400);
FORCEPROP 2 LAST SIG_NAME SGPIO_OCP_V3_2_DATAIN
J 0
(-2560 4410);
DISPLAY 0.510638 (-2560 4410);
PAINT WHITE (-2560 4410);
WIRE 16 -1 (-3775 4350)(-1825 4350);
FORCEPROP 2 LAST SIG_NAME SGPIO_OCP_V3_2_DATAOUT
J 0
(-2560 4360);
DISPLAY 0.510638 (-2560 4360);
PAINT WHITE (-2560 4360);
WIRE 16 -1 (-3775 4250)(-1825 4250);
FORCEPROP 2 LAST SIG_NAME SCM_SPARE_0
J 0
(-2560 4260);
DISPLAY 0.510638 (-2560 4260);
PAINT WHITE (-2560 4260);
WIRE 16 -1 (-3775 4300)(-1825 4300);
FORCEPROP 2 LAST SIG_NAME SGPIO_OCP_V3_2_CLK
J 0
(-2560 4310);
DISPLAY 0.510638 (-2560 4310);
PAINT WHITE (-2560 4310);
WIRE 16 -1 (-1825 4700)(-3775 4700);
FORCEPROP 2 LAST SIG_NAME FM_UARTSW_MSB_N
J 0
(-2560 4710);
DISPLAY 0.510638 (-2560 4710);
PAINT WHITE (-2560 4710);
WIRE 16 -1 (-2675 4750)(-1825 4750);
FORCEPROP 2 LAST SIG_NAME P12V_OCP_V3_2_PLD_PWRGD
J 0
(-2535 4760);
DISPLAY 0.489362 (-2535 4760);
WIRE 16 -1 (-2675 4800)(-1825 4800);
FORCEPROP 0 LAST CDS_PHYS_NET_NAME GPU_3V3IO_RSVD3_FFU_ISO
J 0
(-2650 4842);
PAINT MONO (-2650 4842);
DISPLAY INVISIBLE (-2650 4842);
FORCEPROP 0 LAST SIG_NAME GPU_3V3IO_RSVD3_FFU_ISO
J 0
(-2560 4810);
DISPLAY 0.553191 (-2560 4810);
PAINT WHITE (-2560 4810);
WIRE 16 -1 (-2675 4850)(-1825 4850);
FORCEPROP 0 LAST CDS_PHYS_NET_NAME GPU_3V3IO_RSVD2_FFU_ISO
J 0
(-2650 4892);
PAINT MONO (-2650 4892);
DISPLAY INVISIBLE (-2650 4892);
FORCEPROP 0 LAST SIG_NAME PRSNT_CABLE_GPU_B3_ISO_N
J 0
(-2560 4860);
DISPLAY 0.553191 (-2560 4860);
PAINT WHITE (-2560 4860);
WIRE 16 -1 (-3775 4100)(-2875 4100);
FORCEPROP 2 LAST SIG_NAME SCM_SYS_PWROK
J 0
(-3650 4110);
DISPLAY 0.489362 (-3650 4110);
FORCEPROP 2 LASTPROP $XRERR UNIQUE?
J 0
(-3890 4110);
DISPLAY 0.638298 (-3890 4110);
PAINT MONO (-3890 4110);
DISPLAY INVISIBLE (-3890 4110);
WIRE 16 -1 (-1825 4000)(-3775 4000);
FORCEPROP 2 LAST SIG_NAME PVDDCR_SOC_P1_EN
J 0
(-2560 4010);
DISPLAY 0.489362 (-2560 4010);
WIRE 16 -1 (-1825 3850)(-3775 3850);
FORCEPROP 2 LAST SIG_NAME PVDDCR_CPU0_P0_EN
J 0
(-2560 3860);
DISPLAY 0.489362 (-2560 3860);
WIRE 16 -1 (-3175 2750)(-1825 2750);
FORCEPROP 2 LAST SIG_NAME SMB_BMC_SWB_EN
J 0
(-2560 2760);
DISPLAY 0.553191 (-2560 2760);
WIRE 16 -1 (-3775 2750)(-3175 2750);
WIRE 16 -1 (-3775 4750)(-2875 4750);
FORCEPROP 2 LAST SIG_NAME HP_LVC3_OCP_V3_2_P12V_PWRGD_R
J 0
(-3650 4750);
DISPLAY 0.489362 (-3650 4750);
FORCEPROP 2 LASTPROP $XRERR UNIQUE?
J 0
(-3890 4750);
DISPLAY 0.638298 (-3890 4750);
PAINT MONO (-3890 4750);
DISPLAY INVISIBLE (-3890 4750);
WIRE 16 -1 (-2675 3950)(-1825 3950);
FORCEPROP 0 LAST SIG_NAME HP_LVC3_OCP_V3_2_PRSNT2_PLD_N
J 0
(-2560 3960);
DISPLAY 0.553191 (-2560 3960);
PAINT WHITE (-2560 3960);
WIRE 16 -1 (-5875 4150)(-8275 4150);
FORCEPROP 2 LAST SIG_NAME E1S_0_PERST1_CLKREQ_R_N
J 0
(-7700 4160);
DISPLAY 0.553191 (-7700 4160);
PAINT WHITE (-7700 4160);
FORCEPROP 2 LASTPROP $XRERR UNIQUE?
J 0
(-7940 4160);
DISPLAY 0.638298 (-7940 4160);
PAINT MONO (-7940 4160);
DISPLAY INVISIBLE (-7940 4160);
WIRE 16 -1 (-8275 4150)(-8275 4300);
WIRE 16 -1 (-8350 4150)(-8275 4150);
WIRE 16 -1 (-8275 4300)(-8350 4300);
WIRE 16 -1 (-5875 3600)(-7825 3600);
FORCEPROP 2 LAST SIG_NAME SGPIO_OCP_SFF_CLK
J 0
(-7700 3610);
DISPLAY 0.510638 (-7700 3610);
PAINT WHITE (-7700 3610);
WIRE 16 -1 (-5875 3550)(-7825 3550);
FORCEPROP 2 LAST SIG_NAME OCP_V3_2_MAIN_PWR_EN
J 0
(-7700 3560);
DISPLAY 0.510638 (-7700 3560);
PAINT WHITE (-7700 3560);
WIRE 16 -1 (-5875 3350)(-7825 3350);
FORCEPROP 2 LAST SIG_NAME OCP_V3_1_P3V3_PLD_R_PWRGD
J 0
(-7700 3360);
DISPLAY 0.574468 (-7700 3360);
WIRE 16 -1 (-5875 3300)(-6750 3300);
FORCEPROP 2 LAST SIG_NAME P12V_OCP_SFF_EN
J 0
(-6460 3300);
DISPLAY 0.489362 (-6460 3300);
FORCEPROP 2 LASTPROP $XRERR UNIQUE?
J 0
(-6700 3300);
DISPLAY 0.638298 (-6700 3300);
PAINT MONO (-6700 3300);
DISPLAY INVISIBLE (-6700 3300);
WIRE 16 -1 (-7825 3250)(-5875 3250);
FORCEPROP 2 LAST SIG_NAME FM_BOARD_BMC_SKU_ID1
J 0
(-7695 3260);
DISPLAY 0.553191 (-7695 3260);
PAINT WHITE (-7695 3260);
WIRE 16 -1 (-7825 3200)(-5875 3200);
FORCEPROP 2 LAST SIG_NAME FM_BOARD_BMC_SKU_ID2
J 0
(-7695 3210);
DISPLAY 0.553191 (-7695 3210);
PAINT WHITE (-7695 3210);
WIRE 16 -1 (-5875 3150)(-7825 3150);
FORCEPROP 0 LAST SIG_NAME FM_LED_ACTIVE_E1S_0
J 0
(-7700 3160);
DISPLAY 0.489362 (-7700 3160);
WIRE 16 -1 (-5875 4100)(-7825 4100);
FORCEPROP 2 LAST SIG_NAME SGPIO_SCM_CLK_<0>
J 0
(-7700 4110);
DISPLAY 0.510638 (-7700 4110);
PAINT WHITE (-7700 4110);
WIRE 16 -1 (-5875 3650)(-7825 3650);
FORCEPROP 2 LAST SIG_NAME SGPIO_OCP_SFF_DATAOUT
J 0
(-7700 3660);
DISPLAY 0.510638 (-7700 3660);
PAINT WHITE (-7700 3660);
WIRE 16 -1 (-7825 3400)(-6950 3400);
FORCEPROP 2 LAST SIG_NAME P3V3_OCP_SFF_EN_R
J 0
(-7700 3410);
DISPLAY 0.489362 (-7700 3410);
WIRE 16 -1 (-6950 3300)(-7825 3300);
FORCEPROP 2 LAST SIG_NAME P12V_OCP_SFF_EN_R
J 0
(-7700 3310);
DISPLAY 0.489362 (-7700 3310);
WIRE 16 -1 (-6750 3400)(-5875 3400);
FORCEPROP 2 LAST SIG_NAME P3V3_OCP_SFF_EN
J 0
(-6650 3410);
DISPLAY 0.489362 (-6650 3410);
FORCEPROP 2 LASTPROP $XRERR UNIQUE?
J 0
(-6890 3410);
DISPLAY 0.638298 (-6890 3410);
PAINT MONO (-6890 3410);
DISPLAY INVISIBLE (-6890 3410);
WIRE 16 -1 (-5875 3700)(-7825 3700);
FORCEPROP 2 LAST SIG_NAME SGPIO_OCP_SFF_DATAIN
J 0
(-7700 3710);
DISPLAY 0.510638 (-7700 3710);
PAINT WHITE (-7700 3710);
WIRE 16 -1 (-5875 3750)(-7825 3750);
FORCEPROP 2 LAST SIG_NAME SGPIO_OCP_SFF_LD_N
J 0
(-7700 3760);
DISPLAY 0.510638 (-7700 3760);
PAINT WHITE (-7700 3760);
WIRE 16 -1 (-7825 3100)(-6950 3100);
FORCEPROP 0 LAST SIG_NAME IRQ_UV_DETECT_N
J 0
(-7700 3110);
DISPLAY 0.489362 (-7700 3110);
WIRE 16 -1 (-7825 2950)(-6950 2950);
FORCEPROP 2 LAST SIG_NAME SMB_CPU0_4_XLTR_SDA
J 0
(-7700 2960);
DISPLAY 0.489362 (-7700 2960);
WIRE 16 -1 (-7825 2850)(-5875 2850);
FORCEPROP 2 LAST SIG_NAME FM_BOARD_BMC_SKU_ID3
J 0
(-7695 2860);
DISPLAY 0.553191 (-7695 2860);
PAINT WHITE (-7695 2860);
WIRE 16 -1 (-5875 4050)(-7825 4050);
FORCEPROP 2 LAST SIG_NAME SGPIO_SCM_DO_<0>
J 0
(-7700 4060);
DISPLAY 0.489362 (-7700 4060);
WIRE 16 -1 (-7825 4000)(-6925 4000);
FORCEPROP 2 LAST SIG_NAME IRQ_HSC_FAULT_BUF_N
J 0
(-7700 4010);
DISPLAY 0.553191 (-7700 4010);
PAINT WHITE (-7700 4010);
WIRE 16 -1 (-7825 3950)(-6925 3950);
FORCEPROP 2 LAST SIG_NAME FM_UV_ADR_TRIGGER_N
J 0
(-7700 3960);
DISPLAY 0.553191 (-7700 3960);
PAINT WHITE (-7700 3960);
WIRE 16 -1 (-6925 3900)(-7825 3900);
FORCEPROP 2 LAST SIG_NAME SGPIO_SCM_DI_<1>
J 0
(-7700 3910);
DISPLAY 0.489362 (-7700 3910);
WIRE 16 -1 (-5875 3850)(-7825 3850);
FORCEPROP 2 LAST SIG_NAME SGPIO_SCM_LD_<0>
J 0
(-7700 3860);
DISPLAY 0.489362 (-7700 3860);
WIRE 16 -1 (-5875 3800)(-7825 3800);
FORCEPROP 2 LAST SIG_NAME PCIE_M2_SSD0_PRSNT_N
J 0
(-7700 3810);
DISPLAY 0.510638 (-7700 3810);
PAINT WHITE (-7700 3810);
WIRE 16 -1 (-5875 4200)(-7825 4200);
FORCEPROP 2 LAST SIG_NAME SGPIO_SCM_LD_<1>
J 0
(-7700 4210);
DISPLAY 0.489362 (-7700 4210);
WIRE 16 -1 (-6750 3050)(-5875 3050);
FORCEPROP 2 LAST SIG_NAME OC_ALERT_N
J 0
(-6650 3060);
DISPLAY 0.553191 (-6650 3060);
FORCEPROP 2 LASTPROP $XRERR UNIQUE?
J 0
(-6890 3060);
DISPLAY 0.638298 (-6890 3060);
PAINT MONO (-6890 3060);
DISPLAY INVISIBLE (-6890 3060);
WIRE 16 -1 (-5875 3000)(-6750 3000);
FORCEPROP 2 LAST SIG_NAME SMB_CPU0_4_XLTR_R_SCL
J 0
(-6650 3010);
DISPLAY 0.489362 (-6650 3010);
FORCEPROP 2 LASTPROP $XRERR UNIQUE?
J 0
(-6890 3010);
DISPLAY 0.638298 (-6890 3010);
PAINT MONO (-6890 3010);
DISPLAY INVISIBLE (-6890 3010);
WIRE 16 -1 (-5875 2950)(-6750 2950);
FORCEPROP 2 LAST SIG_NAME SMB_CPU0_4_XLTR_R_SDA
J 0
(-6650 2960);
DISPLAY 0.489362 (-6650 2960);
FORCEPROP 2 LASTPROP $XRERR UNIQUE?
J 0
(-6890 2960);
DISPLAY 0.638298 (-6890 2960);
PAINT MONO (-6890 2960);
DISPLAY INVISIBLE (-6890 2960);
WIRE 16 -1 (-7825 2800)(-5875 2800);
FORCEPROP 2 LAST SIG_NAME FM_BOARD_BMC_SKU_ID4
J 0
(-7695 2810);
DISPLAY 0.553191 (-7695 2810);
PAINT WHITE (-7695 2810);
WIRE 16 -1 (-6750 2700)(-5875 2700);
FORCEPROP 2 LAST SIG_NAME JTAG_SCM_TRST_R_N
J 0
(-6650 2710);
DISPLAY 0.489362 (-6650 2710);
FORCEPROP 2 LASTPROP $XRERR UNIQUE?
J 0
(-6890 2710);
DISPLAY 0.638298 (-6890 2710);
PAINT MONO (-6890 2710);
DISPLAY INVISIBLE (-6890 2710);
WIRE 16 -1 (-6750 3100)(-5875 3100);
FORCEPROP 2 LAST SIG_NAME UV_ALERT_N
J 0
(-6650 3110);
DISPLAY 0.553191 (-6650 3110);
FORCEPROP 2 LASTPROP $XRERR UNIQUE?
J 0
(-6890 3110);
DISPLAY 0.638298 (-6890 3110);
PAINT MONO (-6890 3110);
DISPLAY INVISIBLE (-6890 3110);
WIRE 16 -1 (-2875 4900)(-3775 4900);
FORCEPROP 0 LAST SIG_NAME SMB_1_PLD_3V3AUX_SDA_R2
J 0
(-3650 4900);
DISPLAY 0.553191 (-3650 4900);
PAINT WHITE (-3650 4900);
FORCEPROP 2 LASTPROP $XRERR UNIQUE?
J 0
(-3890 4900);
DISPLAY 0.638298 (-3890 4900);
PAINT MONO (-3890 4900);
DISPLAY INVISIBLE (-3890 4900);
WIRE 16 -1 (-3775 4850)(-2875 4850);
FORCEPROP 0 LAST CDS_PHYS_NET_NAME GPU_3V3IO_RSVD2_FFU_ISO_R
J 0
(-3750 4892);
PAINT MONO (-3750 4892);
DISPLAY INVISIBLE (-3750 4892);
FORCEPROP 0 LAST SIG_NAME PRSNT_CABLE_GPU_B3_ISO_R_N
J 0
(-3650 4860);
DISPLAY 0.553191 (-3650 4860);
PAINT WHITE (-3650 4860);
FORCEPROP 2 LASTPROP $XRERR UNIQUE?
J 0
(-3890 4860);
DISPLAY 0.638298 (-3890 4860);
PAINT MONO (-3890 4860);
DISPLAY INVISIBLE (-3890 4860);
WIRE 16 -1 (-3775 5050)(-1825 5050);
FORCEPROP 0 LAST SIG_NAME FM_FAN_PWR_EN
J 0
(-2560 5060);
DISPLAY 0.553191 (-2560 5060);
PAINT WHITE (-2560 5060);
WIRE 16 -1 (-3775 5000)(-1825 5000);
FORCEPROP 2 LAST SIG_NAME SCM_SYS_PWRBTN_N
J 0
(-3650 5000);
DISPLAY 0.489362 (-3650 5000);
WIRE 16 -1 (-3775 4800)(-2875 4800);
FORCEPROP 0 LAST CDS_PHYS_NET_NAME GPU_3V3IO_RSVD3_FFU_ISO_R
J 0
(-3750 4842);
PAINT MONO (-3750 4842);
DISPLAY INVISIBLE (-3750 4842);
FORCEPROP 0 LAST SIG_NAME GPU_3V3IO_RSVD3_FFU_ISO_R
J 0
(-3650 4810);
DISPLAY 0.553191 (-3650 4810);
PAINT WHITE (-3650 4810);
FORCEPROP 2 LASTPROP $XRERR UNIQUE?
J 0
(-3890 4810);
DISPLAY 0.638298 (-3890 4810);
PAINT MONO (-3890 4810);
DISPLAY INVISIBLE (-3890 4810);
WIRE 16 -1 (-2875 4650)(-3775 4650);
FORCEPROP 0 LAST SIG_NAME SMB_2_PLD_3V3AUX_SCL_R2
J 0
(-3650 4660);
DISPLAY 0.553191 (-3650 4660);
PAINT WHITE (-3650 4660);
FORCEPROP 2 LASTPROP $XRERR UNIQUE?
J 0
(-3890 4660);
DISPLAY 0.638298 (-3890 4660);
PAINT MONO (-3890 4660);
DISPLAY INVISIBLE (-3890 4660);
WIRE 16 -1 (-2675 4900)(-1825 4900);
FORCEPROP 0 LAST SIG_NAME SMB_1_PLD_3V3AUX_SDA_R1
J 0
(-2560 4910);
DISPLAY 0.553191 (-2560 4910);
PAINT WHITE (-2560 4910);
WIRE 16 -1 (-2675 4950)(-1825 4950);
FORCEPROP 0 LAST SIG_NAME SMB_1_PLD_3V3AUX_SCL_R1
J 0
(-2560 4960);
DISPLAY 0.553191 (-2560 4960);
PAINT WHITE (-2560 4960);
WIRE 16 -1 (-6750 4950)(-5875 4950);
FORCEPROP 2 LAST SIG_NAME FM_I3C_CPU1_MUX0_R_SEL
J 0
(-6650 4960);
DISPLAY 0.489362 (-6650 4960);
FORCEPROP 2 LASTPROP $XRERR UNIQUE?
J 0
(-6890 4960);
DISPLAY 0.638298 (-6890 4960);
PAINT MONO (-6890 4960);
DISPLAY INVISIBLE (-6890 4960);
WIRE 16 -1 (-2675 2850)(-1825 2850);
FORCEPROP 2 LAST SIG_NAME CLK_GEN2_GPU_FPGA_OE_N
J 0
(-2560 2860);
DISPLAY 0.510638 (-2560 2860);
PAINT WHITE (-2560 2860);
WIRE 16 -1 (-6750 2750)(-5875 2750);
FORCEPROP 0 LAST CDS_PHYS_NET_NAME FM_SYS_THROTTLE_R_N
J 0
(-6725 2792);
PAINT MONO (-6725 2792);
DISPLAY INVISIBLE (-6725 2792);
FORCEPROP 0 LAST SIG_NAME FM_SYS_THROTTLE_R_N
J 0
(-6650 2760);
DISPLAY 0.489362 (-6650 2760);
FORCEPROP 2 LASTPROP $XRERR UNIQUE?
J 0
(-6890 2760);
DISPLAY 0.638298 (-6890 2760);
PAINT MONO (-6890 2760);
DISPLAY INVISIBLE (-6890 2760);
WIRE 16 -1 (-7825 2750)(-6950 2750);
FORCEPROP 0 LAST CDS_PHYS_NET_NAME FM_SYS_THROTTLE_N
J 0
(-7800 2792);
PAINT MONO (-7800 2792);
DISPLAY INVISIBLE (-7800 2792);
FORCEPROP 0 LAST SIG_NAME FM_SYS_THROTTLE_N
J 0
(-7700 2760);
DISPLAY 0.489362 (-7700 2760);
WIRE 16 -1 (-6950 2700)(-7825 2700);
FORCEPROP 0 LAST CDS_PHYS_NET_NAME JTAG_SCM_TRST_N
J 0
(-7550 2750);
PAINT MONO (-7550 2750);
DISPLAY INVISIBLE (-7550 2750);
FORCEPROP 2 LAST SIG_NAME JTAG_SCM_TRST_N
J 0
(-7700 2710);
DISPLAY 0.489362 (-7700 2710);
WIRE 16 -1 (-7825 4900)(-6950 4900);
FORCEPROP 2 LAST SIG_NAME FM_I3C_CPU1_MUX1_OE_N
J 0
(-7700 4910);
DISPLAY 0.489362 (-7700 4910);
WIRE 16 -1 (-7825 4800)(-6950 4800);
FORCEPROP 2 LAST SIG_NAME FM_I3C_CPU1_MUX0_OE_N
J 0
(-7700 4810);
DISPLAY 0.489362 (-7700 4810);
WIRE 16 -1 (-7825 4750)(-6950 4750);
FORCEPROP 2 LAST SIG_NAME SCM_JTAG_MUX_S1
J 0
(-7700 4760);
DISPLAY 0.489362 (-7700 4760);
WIRE 16 -1 (-7825 4700)(-6950 4700);
FORCEPROP 2 LAST SIG_NAME FM_I3C_CPU0_MUX0_SEL
J 0
(-7700 4710);
DISPLAY 0.489362 (-7700 4710);
WIRE 16 -1 (-6950 4650)(-7825 4650);
FORCEPROP 2 LAST SIG_NAME FM_I3C_CPU0_MUX1_OE_N
J 0
(-7700 4660);
DISPLAY 0.489362 (-7700 4660);
WIRE 16 -1 (-7825 4600)(-6950 4600);
FORCEPROP 2 LAST SIG_NAME SCM_JTAG_MUX_S0
J 0
(-7700 4610);
DISPLAY 0.489362 (-7700 4610);
WIRE 16 -1 (-6725 3900)(-5875 3900);
FORCEPROP 2 LAST SIG_NAME SGPIO_SCM_DI_R<1>
J 0
(-6625 3910);
DISPLAY 0.489362 (-6625 3910);
FORCEPROP 2 LASTPROP $XRERR UNIQUE?
J 0
(-6865 3910);
DISPLAY 0.638298 (-6865 3910);
PAINT MONO (-6865 3910);
DISPLAY INVISIBLE (-6865 3910);
WIRE 16 -1 (-6750 5000)(-5875 5000);
FORCEPROP 2 LAST SIG_NAME FM_I3C_CPU0_MUX0_OE_R_N
J 0
(-6650 5010);
DISPLAY 0.489362 (-6650 5010);
FORCEPROP 2 LASTPROP $XRERR UNIQUE?
J 0
(-6890 5010);
DISPLAY 0.638298 (-6890 5010);
PAINT MONO (-6890 5010);
DISPLAY INVISIBLE (-6890 5010);
WIRE 16 -1 (-6750 4900)(-5875 4900);
FORCEPROP 2 LAST SIG_NAME FM_I3C_CPU1_MUX1_OE_R_N
J 0
(-6650 4910);
DISPLAY 0.489362 (-6650 4910);
FORCEPROP 2 LASTPROP $XRERR UNIQUE?
J 0
(-6890 4910);
DISPLAY 0.638298 (-6890 4910);
PAINT MONO (-6890 4910);
DISPLAY INVISIBLE (-6890 4910);
WIRE 16 -1 (-6750 4850)(-5875 4850);
FORCEPROP 2 LAST SIG_NAME FM_I3C_CPU0_MUX1_R_SEL
J 0
(-6650 4860);
DISPLAY 0.489362 (-6650 4860);
FORCEPROP 2 LASTPROP $XRERR UNIQUE?
J 0
(-6890 4860);
DISPLAY 0.638298 (-6890 4860);
PAINT MONO (-6890 4860);
DISPLAY INVISIBLE (-6890 4860);
WIRE 16 -1 (-6750 4700)(-5875 4700);
FORCEPROP 2 LAST SIG_NAME FM_I3C_CPU0_MUX0_R_SEL
J 0
(-6650 4710);
DISPLAY 0.489362 (-6650 4710);
FORCEPROP 2 LASTPROP $XRERR UNIQUE?
J 0
(-6890 4710);
DISPLAY 0.638298 (-6890 4710);
PAINT MONO (-6890 4710);
DISPLAY INVISIBLE (-6890 4710);
WIRE 16 -1 (-6750 4550)(-5875 4550);
FORCEPROP 2 LAST SIG_NAME SGPIO_SCM_DI_R<0>
J 0
(-6650 4560);
DISPLAY 0.489362 (-6650 4560);
FORCEPROP 2 LASTPROP $XRERR UNIQUE?
J 0
(-6890 4560);
DISPLAY 0.638298 (-6890 4560);
PAINT MONO (-6890 4560);
DISPLAY INVISIBLE (-6890 4560);
WIRE 16 -1 (-5875 4450)(-6750 4450);
FORCEPROP 2 LAST SIG_NAME SGPIO_SCM_INTR_R_N
J 0
(-6650 4460);
DISPLAY 0.489362 (-6650 4460);
FORCEPROP 2 LASTPROP $XRERR UNIQUE?
J 0
(-6890 4460);
DISPLAY 0.638298 (-6890 4460);
PAINT MONO (-6890 4460);
DISPLAY INVISIBLE (-6890 4460);
WIRE 16 -1 (-6750 4800)(-5875 4800);
FORCEPROP 2 LAST SIG_NAME FM_I3C_CPU1_MUX0_OE_R_N
J 0
(-6650 4810);
DISPLAY 0.489362 (-6650 4810);
FORCEPROP 2 LASTPROP $XRERR UNIQUE?
J 0
(-6890 4810);
DISPLAY 0.638298 (-6890 4810);
PAINT MONO (-6890 4810);
DISPLAY INVISIBLE (-6890 4810);
WIRE 16 -1 (-6750 4750)(-5875 4750);
FORCEPROP 2 LAST SIG_NAME SCM_JTAG_MUX_R_S1
J 0
(-6650 4760);
DISPLAY 0.489362 (-6650 4760);
FORCEPROP 2 LASTPROP $XRERR UNIQUE?
J 0
(-6890 4760);
DISPLAY 0.638298 (-6890 4760);
PAINT MONO (-6890 4760);
DISPLAY INVISIBLE (-6890 4760);
WIRE 16 -1 (-6750 4600)(-5875 4600);
FORCEPROP 2 LAST SIG_NAME SCM_JTAG_MUX_R_S0
J 0
(-6650 4610);
DISPLAY 0.489362 (-6650 4610);
FORCEPROP 2 LASTPROP $XRERR UNIQUE?
J 0
(-6890 4610);
DISPLAY 0.638298 (-6890 4610);
PAINT MONO (-6890 4610);
DISPLAY INVISIBLE (-6890 4610);
WIRE 16 -1 (-7825 5000)(-6950 5000);
FORCEPROP 2 LAST SIG_NAME FM_I3C_CPU0_MUX0_OE_N
J 0
(-7700 5010);
DISPLAY 0.489362 (-7700 5010);
WIRE 16 -1 (-6950 4450)(-7825 4450);
FORCEPROP 2 LAST SIG_NAME SGPIO_SCM_INTR_N
J 0
(-7700 4460);
DISPLAY 0.489362 (-7700 4460);
WIRE 16 -1 (-6750 4650)(-5875 4650);
FORCEPROP 2 LAST SIG_NAME FM_I3C_CPU0_MUX1_OE_R_N
J 0
(-6650 4660);
DISPLAY 0.489362 (-6650 4660);
FORCEPROP 2 LASTPROP $XRERR UNIQUE?
J 0
(-6890 4660);
DISPLAY 0.638298 (-6890 4660);
PAINT MONO (-6890 4660);
DISPLAY INVISIBLE (-6890 4660);
WIRE 16 -1 (-7825 4300)(-6950 4300);
FORCEPROP 2 LAST SIG_NAME FM_I3C_CPU1_MUX1_SEL
J 0
(-7700 4310);
DISPLAY 0.489362 (-7700 4310);
WIRE 16 -1 (-6950 4550)(-7825 4550);
FORCEPROP 2 LAST SIG_NAME SGPIO_SCM_DI_<0>
J 0
(-7700 4560);
DISPLAY 0.489362 (-7700 4560);
WIRE 16 -1 (-2875 1200)(-4825 1200);
FORCEPROP 2 LAST SIG_NAME CPLD_PROGRAMN
J 0
(-4685 1210);
DISPLAY 0.489362 (-4685 1210);
WIRE 16 -1 (-2875 1350)(-4825 1350);
FORCEPROP 2 LAST SIG_NAME JTAG_SCM_PLD_TCK
J 0
(-4685 1360);
DISPLAY 0.489362 (-4685 1360);
WIRE 16 -1 (-4825 1150)(-2875 1150);
FORCEPROP 2 LAST SIG_NAME VIRTUAL_RESEAT
J 0
(-4685 1160);
DISPLAY 0.510638 (-4685 1160);
PAINT WHITE (-4685 1160);
WIRE 16 -1 (-2875 1250)(-4825 1250);
FORCEPROP 2 LAST SIG_NAME CPLD_JTAG_EN
J 0
(-4685 1260);
DISPLAY 0.489362 (-4685 1260);
WIRE 16 -1 (-2875 1300)(-4825 1300);
FORCEPROP 2 LAST SIG_NAME JTAG_SCM_PLD_TMS
J 0
(-4685 1310);
DISPLAY 0.489362 (-4685 1310);
WIRE 16 -1 (-2875 1400)(-4825 1400);
FORCEPROP 2 LAST SIG_NAME JTAG_SCM_PLD_TDO
J 0
(-4685 1410);
DISPLAY 0.489362 (-4685 1410);
WIRE 16 -1 (-2875 1450)(-4825 1450);
FORCEPROP 2 LAST SIG_NAME JTAG_SCM_PLD_TDI
J 0
(-4685 1460);
DISPLAY 0.489362 (-4685 1460);
WIRE 16 -1 (-9025 4150)(-8550 4150);
FORCEPROP 2 LAST SIG_NAME E1S_0_PRSNT_N
J 0
(-9010 4160);
DISPLAY 0.446809 (-9010 4160);
PAINT WHITE (-9010 4160);
WIRE 16 -1 (-9025 4300)(-8550 4300);
FORCEPROP 2 LAST SIG_NAME E1S_0_PERST1_CLKREQ_N
J 0
(-9010 4310);
DISPLAY 0.446809 (-9010 4310);
PAINT WHITE (-9010 4310);
WIRE 16 -1 (-7825 4850)(-6950 4850);
FORCEPROP 2 LAST SIG_NAME FM_I3C_CPU0_MUX1_SEL
J 0
(-7700 4860);
DISPLAY 0.489362 (-7700 4860);
WIRE 16 -1 (-7825 4950)(-6950 4950);
FORCEPROP 2 LAST SIG_NAME FM_I3C_CPU1_MUX0_SEL
J 0
(-7700 4960);
DISPLAY 0.489362 (-7700 4960);
WIRE 16 -1 (-4825 1100)(-3925 1100);
FORCEPROP 2 LAST SIG_NAME VIRTUAL_RESEAT_FPGA_R_N
J 0
(-4685 1110);
DISPLAY 0.510638 (-4685 1110);
PAINT WHITE (-4685 1110);
FORCEPROP 2 LASTPROP $XRERR UNIQUE?
J 0
(-4925 1110);
DISPLAY 0.638298 (-4925 1110);
PAINT MONO (-4925 1110);
DISPLAY INVISIBLE (-4925 1110);
WIRE 16 -1 (-3725 1100)(-2875 1100);
FORCEPROP 2 LAST SIG_NAME VIRTUAL_RESEAT_FPGA_N
J 0
(-3535 1110);
DISPLAY 0.510638 (-3535 1110);
PAINT WHITE (-3535 1110);
WIRE 16 -1 (-2875 4600)(-3775 4600);
FORCEPROP 0 LAST SIG_NAME SMB_2_PLD_3V3AUX_SDA_R2
J 0
(-3650 4610);
DISPLAY 0.553191 (-3650 4610);
PAINT WHITE (-3650 4610);
FORCEPROP 2 LASTPROP $XRERR UNIQUE?
J 0
(-3890 4610);
DISPLAY 0.638298 (-3890 4610);
PAINT MONO (-3890 4610);
DISPLAY INVISIBLE (-3890 4610);
WIRE 16 -1 (-2875 3950)(-3775 3950);
FORCEPROP 0 LAST SIG_NAME PRSNT_OCP_V3_2_N
J 0
(-3650 3960);
DISPLAY 0.553191 (-3650 3960);
PAINT WHITE (-3650 3960);
FORCEPROP 2 LASTPROP $XRERR UNIQUE?
J 0
(-3890 3960);
DISPLAY 0.638298 (-3890 3960);
PAINT MONO (-3890 3960);
DISPLAY INVISIBLE (-3890 3960);
WIRE 16 -1 (-3775 3800)(-2875 3800);
FORCEPROP 0 LAST SIG_NAME RST_SRST_PLD_BMC_R_N
J 0
(-3610 3810);
DISPLAY 0.446809 (-3610 3810);
PAINT WHITE (-3610 3810);
FORCEPROP 2 LASTPROP $XRERR UNIQUE?
J 0
(-3850 3810);
DISPLAY 0.638298 (-3850 3810);
PAINT MONO (-3850 3810);
DISPLAY INVISIBLE (-3850 3810);
WIRE 16 -1 (-3775 2900)(-2875 2900);
FORCEPROP 2 LAST SIG_NAME CLK_GEN2_BMC_RC_OE_R_N
J 0
(-3650 2910);
DISPLAY 0.510638 (-3650 2910);
PAINT WHITE (-3650 2910);
FORCEPROP 2 LASTPROP $XRERR UNIQUE?
J 0
(-3890 2910);
DISPLAY 0.638298 (-3890 2910);
PAINT MONO (-3890 2910);
DISPLAY INVISIBLE (-3890 2910);
WIRE 16 -1 (-2675 3900)(-1825 3900);
FORCEPROP 2 LAST SIG_NAME PWRGD_P5V_R2
J 0
(-2485 3910);
DISPLAY 0.553191 (-2485 3910);
WIRE 16 -1 (-5875 4350)(-7825 4350);
FORCEPROP 2 LAST SIG_NAME SGPIO_SCM_RESET_N
J 0
(-7700 4360);
DISPLAY 0.489362 (-7700 4360);
WIRE 16 -1 (-5875 4400)(-7825 4400);
FORCEPROP 2 LAST SIG_NAME SGPIO_SCM_DO_<1>
J 0
(-7700 4410);
DISPLAY 0.489362 (-7700 4410);
WIRE 16 -1 (-7825 4500)(-5875 4500);
FORCEPROP 2 LAST SIG_NAME PWRGD_PS_PWROK_PLD_ISO_R
J 0
(-7700 4510);
DISPLAY 0.553191 (-7700 4510);
PAINT WHITE (-7700 4510);
WIRE 16 -1 (-6750 4300)(-5875 4300);
FORCEPROP 2 LAST SIG_NAME FM_I3C_CPU1_MUX1_R_SEL
J 0
(-6650 4310);
DISPLAY 0.489362 (-6650 4310);
FORCEPROP 2 LASTPROP $XRERR UNIQUE?
J 0
(-6890 4310);
DISPLAY 0.638298 (-6890 4310);
PAINT MONO (-6890 4310);
DISPLAY INVISIBLE (-6890 4310);
WIRE 16 -1 (-7825 4250)(-5875 4250);
FORCEPROP 2 LAST SIG_NAME FM_BOARD_BMC_SKU_ID0
J 0
(-7700 4260);
DISPLAY 0.553191 (-7700 4260);
PAINT WHITE (-7700 4260);
WIRE 16 -1 (-6725 3950)(-5875 3950);
FORCEPROP 2 LAST SIG_NAME FM_UV_ADR_TRIGGER_R_N
J 0
(-6660 3960);
DISPLAY 0.553191 (-6660 3960);
PAINT WHITE (-6660 3960);
FORCEPROP 2 LASTPROP $XRERR UNIQUE?
J 0
(-6900 3960);
DISPLAY 0.638298 (-6900 3960);
PAINT MONO (-6900 3960);
DISPLAY INVISIBLE (-6900 3960);
WIRE 16 -1 (-6725 4000)(-5875 4000);
FORCEPROP 2 LAST SIG_NAME IRQ_HSC_FAULT_BUF_R_N
J 0
(-6660 4010);
DISPLAY 0.553191 (-6660 4010);
PAINT WHITE (-6660 4010);
FORCEPROP 2 LASTPROP $XRERR UNIQUE?
J 0
(-6900 4010);
DISPLAY 0.638298 (-6900 4010);
PAINT MONO (-6900 4010);
DISPLAY INVISIBLE (-6900 4010);
WIRE 16 -1 (-7825 3050)(-6950 3050);
FORCEPROP 2 LAST SIG_NAME HSC_D_OC
J 0
(-7700 3060);
DISPLAY 0.553191 (-7700 3060);
WIRE 16 -1 (-3775 2700)(-1825 2700);
FORCEPROP 2 LAST SIG_NAME FM_OCP_V3_2_PWR_GOOD
J 0
(-2560 2710);
DISPLAY 0.553191 (-2560 2710);
PAINT WHITE (-2560 2710);
CIRCLE (-1975 3925)(-1808 3925);
PAINT YELLOW (-1975 3925);
CIRCLE (-3175 2750)(-3008 2750);
PAINT YELLOW (-3175 2750);
DOT 1 (-8275 4150);
CIRCLE (-2000 3325)(-1833 3325);
PAINT YELLOW (-2000 3325);
FORCENOTE
TBC
(-2025 3300) 0;
DISPLAY LEFT (-2025 3300);
DISPLAY 1.021277 (-2025 3300);
FORCENOTE
TBC
(-2000 3900) 0;
DISPLAY LEFT (-2000 3900);
DISPLAY 1.021277 (-2000 3900);
FORCENOTE
TBC
(-3200 2725) 0;
DISPLAY LEFT (-3200 2725);
DISPLAY 1.021277 (-3200 2725);
FORCENOTE
BANK0 P3V3_AUX
(-5750 5800) 0;
DISPLAY LEFT (-5750 5800);
DISPLAY 3.148936 (-5750 5800);
QUIT
